FILE_TYPE = MACRO_DRAWING;
SET COLOR_WIRE YELLOW;
SET COLOR_PROP MONO;
SET COLOR_DOT WHITE;
SET COLOR_ARC YELLOW;
SET COLOR_BODY GREEN;
SET COLOR_NOTE MONO;
SET PROP_DISPLAY VALUE;
SET PAGE_NUMBER P65;
FORCEADD TAP..1
R 2
(-5575 2125);
FORCEPROP 3 LASTPIN (-5525 2125) SIG_NAME TP_P3E_CPU1_PE2_RSR_RXN<4>
J 0
(-5515 2135);
DISPLAY 0.659574 (-5515 2135);
PAINT MONO (-5515 2135);
DISPLAY INVISIBLE (-5515 2135);
FORCEPROP 1 LASTPIN (-5525 2125) BN 4
J 2
(-5513 2133);
DISPLAY 0.617021 (-5513 2133);
PAINT GREEN (-5513 2133);
FORCEPROP 2 LAST CDS_LIB mstr_standard
J 0
(-5575 2125);
PAINT MONO (-5575 2125);
DISPLAY INVISIBLE (-5575 2125);
FORCEPROP 1 LAST BODY_TYPE PLUMBING
J 2
(-5575 2175);
DISPLAY 1.446809 (-5575 2175);
PAINT GREEN (-5575 2175);
DISPLAY INVISIBLE (-5575 2175);
FORCEPROP 1 LAST HDL_TAP TRUE
J 2
(-5900 2000);
DISPLAY 1.446809 (-5900 2000);
PAINT GREEN (-5900 2000);
DISPLAY INVISIBLE (-5900 2000);
FORCEPROP 1 LAST PATH I11
J 2
(-5573 2125);
DISPLAY 0.872340 (-5573 2125);
PAINT GREEN (-5573 2125);
DISPLAY INVISIBLE (-5573 2125);
FORCEADD TAP..1
R 2
(-5575 2225);
FORCEPROP 3 LASTPIN (-5525 2225) SIG_NAME TP_P3E_CPU1_PE2_RSR_RXN<6>
J 0
(-5515 2235);
DISPLAY 0.659574 (-5515 2235);
PAINT MONO (-5515 2235);
DISPLAY INVISIBLE (-5515 2235);
FORCEPROP 1 LASTPIN (-5525 2225) BN 6
J 2
(-5513 2233);
DISPLAY 0.617021 (-5513 2233);
PAINT GREEN (-5513 2233);
FORCEPROP 2 LAST CDS_LIB mstr_standard
J 0
(-5575 2225);
PAINT MONO (-5575 2225);
DISPLAY INVISIBLE (-5575 2225);
FORCEPROP 1 LAST BODY_TYPE PLUMBING
J 2
(-5575 2275);
DISPLAY 1.446809 (-5575 2275);
PAINT GREEN (-5575 2275);
DISPLAY INVISIBLE (-5575 2275);
FORCEPROP 1 LAST HDL_TAP TRUE
J 2
(-5900 2100);
DISPLAY 1.446809 (-5900 2100);
PAINT GREEN (-5900 2100);
DISPLAY INVISIBLE (-5900 2100);
FORCEPROP 1 LAST PATH I12
J 2
(-5573 2225);
DISPLAY 0.872340 (-5573 2225);
PAINT GREEN (-5573 2225);
DISPLAY INVISIBLE (-5573 2225);
FORCEADD TAP..1
R 2
(-5575 2175);
FORCEPROP 3 LASTPIN (-5525 2175) SIG_NAME TP_P3E_CPU1_PE2_RSR_RXN<5>
J 0
(-5515 2185);
DISPLAY 0.659574 (-5515 2185);
PAINT MONO (-5515 2185);
DISPLAY INVISIBLE (-5515 2185);
FORCEPROP 1 LASTPIN (-5525 2175) BN 5
J 2
(-5513 2183);
DISPLAY 0.617021 (-5513 2183);
PAINT GREEN (-5513 2183);
FORCEPROP 2 LAST CDS_LIB mstr_standard
J 0
(-5575 2175);
PAINT MONO (-5575 2175);
DISPLAY INVISIBLE (-5575 2175);
FORCEPROP 1 LAST BODY_TYPE PLUMBING
J 2
(-5575 2225);
DISPLAY 1.446809 (-5575 2225);
PAINT GREEN (-5575 2225);
DISPLAY INVISIBLE (-5575 2225);
FORCEPROP 1 LAST HDL_TAP TRUE
J 2
(-5900 2050);
DISPLAY 1.446809 (-5900 2050);
PAINT GREEN (-5900 2050);
DISPLAY INVISIBLE (-5900 2050);
FORCEPROP 1 LAST PATH I13
J 2
(-5573 2175);
DISPLAY 0.872340 (-5573 2175);
PAINT GREEN (-5573 2175);
DISPLAY INVISIBLE (-5573 2175);
FORCEADD TAP..1
R 2
(-5575 2275);
FORCEPROP 3 LASTPIN (-5525 2275) SIG_NAME TP_P3E_CPU1_PE2_RSR_RXN<7>
J 0
(-5515 2285);
DISPLAY 0.659574 (-5515 2285);
PAINT MONO (-5515 2285);
DISPLAY INVISIBLE (-5515 2285);
FORCEPROP 1 LASTPIN (-5525 2275) BN 7
J 2
(-5513 2283);
DISPLAY 0.617021 (-5513 2283);
PAINT GREEN (-5513 2283);
FORCEPROP 2 LAST CDS_LIB mstr_standard
J 0
(-5575 2275);
PAINT MONO (-5575 2275);
DISPLAY INVISIBLE (-5575 2275);
FORCEPROP 1 LAST BODY_TYPE PLUMBING
J 2
(-5575 2325);
DISPLAY 1.446809 (-5575 2325);
PAINT GREEN (-5575 2325);
DISPLAY INVISIBLE (-5575 2325);
FORCEPROP 1 LAST HDL_TAP TRUE
J 2
(-5900 2150);
DISPLAY 1.446809 (-5900 2150);
PAINT GREEN (-5900 2150);
DISPLAY INVISIBLE (-5900 2150);
FORCEPROP 1 LAST PATH I14
J 2
(-5573 2275);
DISPLAY 0.872340 (-5573 2275);
PAINT GREEN (-5573 2275);
DISPLAY INVISIBLE (-5573 2275);
FORCEADD TAP..1
R 2
(-5425 2025);
FORCEPROP 3 LASTPIN (-5375 2025) SIG_NAME TP_P3E_CPU1_PE2_RSR_RXP<3>
J 0
(-5365 2035);
DISPLAY 0.659574 (-5365 2035);
PAINT MONO (-5365 2035);
DISPLAY INVISIBLE (-5365 2035);
FORCEPROP 1 LASTPIN (-5375 2025) BN 3
J 2
(-5363 2033);
DISPLAY 0.617021 (-5363 2033);
PAINT GREEN (-5363 2033);
FORCEPROP 2 LAST CDS_LIB mstr_standard
J 0
(-5425 2025);
PAINT MONO (-5425 2025);
DISPLAY INVISIBLE (-5425 2025);
FORCEPROP 1 LAST BODY_TYPE PLUMBING
J 2
(-5425 2075);
DISPLAY 1.446809 (-5425 2075);
PAINT GREEN (-5425 2075);
DISPLAY INVISIBLE (-5425 2075);
FORCEPROP 1 LAST HDL_TAP TRUE
J 2
(-5750 1900);
DISPLAY 1.446809 (-5750 1900);
PAINT GREEN (-5750 1900);
DISPLAY INVISIBLE (-5750 1900);
FORCEPROP 1 LAST PATH I15
J 2
(-5423 2025);
DISPLAY 0.872340 (-5423 2025);
PAINT GREEN (-5423 2025);
DISPLAY INVISIBLE (-5423 2025);
FORCEADD TAP..1
R 2
(-5425 2375);
FORCEPROP 3 LASTPIN (-5375 2375) SIG_NAME TP_P3E_CPU1_PE2_RSR_RXP<4>
J 0
(-5365 2385);
DISPLAY 0.659574 (-5365 2385);
PAINT MONO (-5365 2385);
DISPLAY INVISIBLE (-5365 2385);
FORCEPROP 1 LASTPIN (-5375 2375) BN 4
J 2
(-5363 2383);
DISPLAY 0.617021 (-5363 2383);
PAINT GREEN (-5363 2383);
FORCEPROP 2 LAST CDS_LIB mstr_standard
J 0
(-5425 2375);
PAINT MONO (-5425 2375);
DISPLAY INVISIBLE (-5425 2375);
FORCEPROP 1 LAST BODY_TYPE PLUMBING
J 2
(-5425 2425);
DISPLAY 1.446809 (-5425 2425);
PAINT GREEN (-5425 2425);
DISPLAY INVISIBLE (-5425 2425);
FORCEPROP 1 LAST HDL_TAP TRUE
J 2
(-5750 2250);
DISPLAY 1.446809 (-5750 2250);
PAINT GREEN (-5750 2250);
DISPLAY INVISIBLE (-5750 2250);
FORCEPROP 1 LAST PATH I16
J 2
(-5423 2375);
DISPLAY 0.872340 (-5423 2375);
PAINT GREEN (-5423 2375);
DISPLAY INVISIBLE (-5423 2375);
FORCEADD TAP..1
R 2
(-5425 2425);
FORCEPROP 3 LASTPIN (-5375 2425) SIG_NAME TP_P3E_CPU1_PE2_RSR_RXP<5>
J 0
(-5365 2435);
DISPLAY 0.659574 (-5365 2435);
PAINT MONO (-5365 2435);
DISPLAY INVISIBLE (-5365 2435);
FORCEPROP 1 LASTPIN (-5375 2425) BN 5
J 2
(-5363 2433);
DISPLAY 0.617021 (-5363 2433);
PAINT GREEN (-5363 2433);
FORCEPROP 2 LAST CDS_LIB mstr_standard
J 0
(-5425 2425);
PAINT MONO (-5425 2425);
DISPLAY INVISIBLE (-5425 2425);
FORCEPROP 1 LAST BODY_TYPE PLUMBING
J 2
(-5425 2475);
DISPLAY 1.446809 (-5425 2475);
PAINT GREEN (-5425 2475);
DISPLAY INVISIBLE (-5425 2475);
FORCEPROP 1 LAST HDL_TAP TRUE
J 2
(-5750 2300);
DISPLAY 1.446809 (-5750 2300);
PAINT GREEN (-5750 2300);
DISPLAY INVISIBLE (-5750 2300);
FORCEPROP 1 LAST PATH I17
J 2
(-5423 2425);
DISPLAY 0.872340 (-5423 2425);
PAINT GREEN (-5423 2425);
DISPLAY INVISIBLE (-5423 2425);
FORCEADD TAP..1
R 2
(-5425 2475);
FORCEPROP 3 LASTPIN (-5375 2475) SIG_NAME TP_P3E_CPU1_PE2_RSR_RXP<6>
J 0
(-5365 2485);
DISPLAY 0.659574 (-5365 2485);
PAINT MONO (-5365 2485);
DISPLAY INVISIBLE (-5365 2485);
FORCEPROP 1 LASTPIN (-5375 2475) BN 6
J 2
(-5363 2483);
DISPLAY 0.617021 (-5363 2483);
PAINT GREEN (-5363 2483);
FORCEPROP 2 LAST CDS_LIB mstr_standard
J 0
(-5425 2475);
PAINT MONO (-5425 2475);
DISPLAY INVISIBLE (-5425 2475);
FORCEPROP 1 LAST BODY_TYPE PLUMBING
J 2
(-5425 2525);
DISPLAY 1.446809 (-5425 2525);
PAINT GREEN (-5425 2525);
DISPLAY INVISIBLE (-5425 2525);
FORCEPROP 1 LAST HDL_TAP TRUE
J 2
(-5750 2350);
DISPLAY 1.446809 (-5750 2350);
PAINT GREEN (-5750 2350);
DISPLAY INVISIBLE (-5750 2350);
FORCEPROP 1 LAST PATH I18
J 2
(-5423 2475);
DISPLAY 0.872340 (-5423 2475);
PAINT GREEN (-5423 2475);
DISPLAY INVISIBLE (-5423 2475);
FORCEADD TAP..1
R 2
(-5575 2625);
FORCEPROP 3 LASTPIN (-5525 2625) SIG_NAME TP_P3E_CPU1_PE2_RSR_RXN<8>
J 0
(-5515 2635);
DISPLAY 0.659574 (-5515 2635);
PAINT MONO (-5515 2635);
DISPLAY INVISIBLE (-5515 2635);
FORCEPROP 1 LASTPIN (-5525 2625) BN 8
J 2
(-5513 2633);
DISPLAY 0.617021 (-5513 2633);
PAINT GREEN (-5513 2633);
FORCEPROP 2 LAST CDS_LIB mstr_standard
J 0
(-5575 2625);
PAINT MONO (-5575 2625);
DISPLAY INVISIBLE (-5575 2625);
FORCEPROP 1 LAST BODY_TYPE PLUMBING
J 2
(-5575 2675);
DISPLAY 1.446809 (-5575 2675);
PAINT GREEN (-5575 2675);
DISPLAY INVISIBLE (-5575 2675);
FORCEPROP 1 LAST HDL_TAP TRUE
J 2
(-5900 2500);
DISPLAY 1.446809 (-5900 2500);
PAINT GREEN (-5900 2500);
DISPLAY INVISIBLE (-5900 2500);
FORCEPROP 1 LAST PATH I19
J 2
(-5573 2625);
DISPLAY 0.872340 (-5573 2625);
PAINT GREEN (-5573 2625);
DISPLAY INVISIBLE (-5573 2625);
FORCEADD TAP..1
R 2
(-5575 2725);
FORCEPROP 3 LASTPIN (-5525 2725) SIG_NAME TP_P3E_CPU1_PE2_RSR_RXN<10>
J 0
(-5515 2735);
DISPLAY 0.659574 (-5515 2735);
PAINT MONO (-5515 2735);
DISPLAY INVISIBLE (-5515 2735);
FORCEPROP 1 LASTPIN (-5525 2725) BN 10
J 2
(-5513 2733);
DISPLAY 0.617021 (-5513 2733);
PAINT GREEN (-5513 2733);
FORCEPROP 2 LAST CDS_LIB mstr_standard
J 0
(-5575 2725);
PAINT MONO (-5575 2725);
DISPLAY INVISIBLE (-5575 2725);
FORCEPROP 1 LAST BODY_TYPE PLUMBING
J 2
(-5575 2775);
DISPLAY 1.446809 (-5575 2775);
PAINT GREEN (-5575 2775);
DISPLAY INVISIBLE (-5575 2775);
FORCEPROP 1 LAST HDL_TAP TRUE
J 2
(-5900 2600);
DISPLAY 1.446809 (-5900 2600);
PAINT GREEN (-5900 2600);
DISPLAY INVISIBLE (-5900 2600);
FORCEPROP 1 LAST PATH I20
J 2
(-5573 2725);
DISPLAY 0.872340 (-5573 2725);
PAINT GREEN (-5573 2725);
DISPLAY INVISIBLE (-5573 2725);
FORCEADD TAP..1
R 2
(-5575 2675);
FORCEPROP 3 LASTPIN (-5525 2675) SIG_NAME TP_P3E_CPU1_PE2_RSR_RXN<9>
J 0
(-5515 2685);
DISPLAY 0.659574 (-5515 2685);
PAINT MONO (-5515 2685);
DISPLAY INVISIBLE (-5515 2685);
FORCEPROP 1 LASTPIN (-5525 2675) BN 9
J 2
(-5513 2683);
DISPLAY 0.617021 (-5513 2683);
PAINT GREEN (-5513 2683);
FORCEPROP 2 LAST CDS_LIB mstr_standard
J 0
(-5575 2675);
PAINT MONO (-5575 2675);
DISPLAY INVISIBLE (-5575 2675);
FORCEPROP 1 LAST BODY_TYPE PLUMBING
J 2
(-5575 2725);
DISPLAY 1.446809 (-5575 2725);
PAINT GREEN (-5575 2725);
DISPLAY INVISIBLE (-5575 2725);
FORCEPROP 1 LAST HDL_TAP TRUE
J 2
(-5900 2550);
DISPLAY 1.446809 (-5900 2550);
PAINT GREEN (-5900 2550);
DISPLAY INVISIBLE (-5900 2550);
FORCEPROP 1 LAST PATH I21
J 2
(-5573 2675);
DISPLAY 0.872340 (-5573 2675);
PAINT GREEN (-5573 2675);
DISPLAY INVISIBLE (-5573 2675);
FORCEADD TAP..1
R 2
(-5575 2775);
FORCEPROP 3 LASTPIN (-5525 2775) SIG_NAME TP_P3E_CPU1_PE2_RSR_RXN<11>
J 0
(-5515 2785);
DISPLAY 0.659574 (-5515 2785);
PAINT MONO (-5515 2785);
DISPLAY INVISIBLE (-5515 2785);
FORCEPROP 1 LASTPIN (-5525 2775) BN 11
J 2
(-5513 2783);
DISPLAY 0.617021 (-5513 2783);
PAINT GREEN (-5513 2783);
FORCEPROP 2 LAST CDS_LIB mstr_standard
J 0
(-5575 2775);
PAINT MONO (-5575 2775);
DISPLAY INVISIBLE (-5575 2775);
FORCEPROP 1 LAST BODY_TYPE PLUMBING
J 2
(-5575 2825);
DISPLAY 1.446809 (-5575 2825);
PAINT GREEN (-5575 2825);
DISPLAY INVISIBLE (-5575 2825);
FORCEPROP 1 LAST HDL_TAP TRUE
J 2
(-5900 2650);
DISPLAY 1.446809 (-5900 2650);
PAINT GREEN (-5900 2650);
DISPLAY INVISIBLE (-5900 2650);
FORCEPROP 1 LAST PATH I22
J 2
(-5573 2775);
DISPLAY 0.872340 (-5573 2775);
PAINT GREEN (-5573 2775);
DISPLAY INVISIBLE (-5573 2775);
FORCEADD TAP..1
R 2
(-5425 2525);
FORCEPROP 3 LASTPIN (-5375 2525) SIG_NAME TP_P3E_CPU1_PE2_RSR_RXP<7>
J 0
(-5365 2535);
DISPLAY 0.659574 (-5365 2535);
PAINT MONO (-5365 2535);
DISPLAY INVISIBLE (-5365 2535);
FORCEPROP 1 LASTPIN (-5375 2525) BN 7
J 2
(-5363 2533);
DISPLAY 0.617021 (-5363 2533);
PAINT GREEN (-5363 2533);
FORCEPROP 2 LAST CDS_LIB mstr_standard
J 0
(-5425 2525);
PAINT MONO (-5425 2525);
DISPLAY INVISIBLE (-5425 2525);
FORCEPROP 1 LAST BODY_TYPE PLUMBING
J 2
(-5425 2575);
DISPLAY 1.446809 (-5425 2575);
PAINT GREEN (-5425 2575);
DISPLAY INVISIBLE (-5425 2575);
FORCEPROP 1 LAST HDL_TAP TRUE
J 2
(-5750 2400);
DISPLAY 1.446809 (-5750 2400);
PAINT GREEN (-5750 2400);
DISPLAY INVISIBLE (-5750 2400);
FORCEPROP 1 LAST PATH I23
J 2
(-5423 2525);
DISPLAY 0.872340 (-5423 2525);
PAINT GREEN (-5423 2525);
DISPLAY INVISIBLE (-5423 2525);
FORCEADD TAP..1
R 2
(-5425 2875);
FORCEPROP 3 LASTPIN (-5375 2875) SIG_NAME TP_P3E_CPU1_PE2_RSR_RXP<8>
J 0
(-5365 2885);
DISPLAY 0.659574 (-5365 2885);
PAINT MONO (-5365 2885);
DISPLAY INVISIBLE (-5365 2885);
FORCEPROP 1 LASTPIN (-5375 2875) BN 8
J 2
(-5363 2883);
DISPLAY 0.617021 (-5363 2883);
PAINT GREEN (-5363 2883);
FORCEPROP 2 LAST CDS_LIB mstr_standard
J 0
(-5425 2875);
PAINT MONO (-5425 2875);
DISPLAY INVISIBLE (-5425 2875);
FORCEPROP 1 LAST BODY_TYPE PLUMBING
J 2
(-5425 2925);
DISPLAY 1.446809 (-5425 2925);
PAINT GREEN (-5425 2925);
DISPLAY INVISIBLE (-5425 2925);
FORCEPROP 1 LAST HDL_TAP TRUE
J 2
(-5750 2750);
DISPLAY 1.446809 (-5750 2750);
PAINT GREEN (-5750 2750);
DISPLAY INVISIBLE (-5750 2750);
FORCEPROP 1 LAST PATH I24
J 2
(-5423 2875);
DISPLAY 0.872340 (-5423 2875);
PAINT GREEN (-5423 2875);
DISPLAY INVISIBLE (-5423 2875);
FORCEADD TAP..1
R 2
(-5425 2925);
FORCEPROP 3 LASTPIN (-5375 2925) SIG_NAME TP_P3E_CPU1_PE2_RSR_RXP<9>
J 0
(-5365 2935);
DISPLAY 0.659574 (-5365 2935);
PAINT MONO (-5365 2935);
DISPLAY INVISIBLE (-5365 2935);
FORCEPROP 1 LASTPIN (-5375 2925) BN 9
J 2
(-5363 2933);
DISPLAY 0.617021 (-5363 2933);
PAINT GREEN (-5363 2933);
FORCEPROP 2 LAST CDS_LIB mstr_standard
J 0
(-5425 2925);
PAINT MONO (-5425 2925);
DISPLAY INVISIBLE (-5425 2925);
FORCEPROP 1 LAST BODY_TYPE PLUMBING
J 2
(-5425 2975);
DISPLAY 1.446809 (-5425 2975);
PAINT GREEN (-5425 2975);
DISPLAY INVISIBLE (-5425 2975);
FORCEPROP 1 LAST HDL_TAP TRUE
J 2
(-5750 2800);
DISPLAY 1.446809 (-5750 2800);
PAINT GREEN (-5750 2800);
DISPLAY INVISIBLE (-5750 2800);
FORCEPROP 1 LAST PATH I25
J 2
(-5423 2925);
DISPLAY 0.872340 (-5423 2925);
PAINT GREEN (-5423 2925);
DISPLAY INVISIBLE (-5423 2925);
FORCEADD TAP..1
R 2
(-5425 2975);
FORCEPROP 3 LASTPIN (-5375 2975) SIG_NAME TP_P3E_CPU1_PE2_RSR_RXP<10>
J 0
(-5365 2985);
DISPLAY 0.659574 (-5365 2985);
PAINT MONO (-5365 2985);
DISPLAY INVISIBLE (-5365 2985);
FORCEPROP 1 LASTPIN (-5375 2975) BN 10
J 2
(-5363 2983);
DISPLAY 0.617021 (-5363 2983);
PAINT GREEN (-5363 2983);
FORCEPROP 2 LAST CDS_LIB mstr_standard
J 0
(-5425 2975);
PAINT MONO (-5425 2975);
DISPLAY INVISIBLE (-5425 2975);
FORCEPROP 1 LAST BODY_TYPE PLUMBING
J 2
(-5425 3025);
DISPLAY 1.446809 (-5425 3025);
PAINT GREEN (-5425 3025);
DISPLAY INVISIBLE (-5425 3025);
FORCEPROP 1 LAST HDL_TAP TRUE
J 2
(-5750 2850);
DISPLAY 1.446809 (-5750 2850);
PAINT GREEN (-5750 2850);
DISPLAY INVISIBLE (-5750 2850);
FORCEPROP 1 LAST PATH I26
J 2
(-5423 2975);
DISPLAY 0.872340 (-5423 2975);
PAINT GREEN (-5423 2975);
DISPLAY INVISIBLE (-5423 2975);
FORCEADD TAP..1
R 2
(-5575 3125);
FORCEPROP 3 LASTPIN (-5525 3125) SIG_NAME TP_P3E_CPU1_PE2_RSR_RXN<12>
J 0
(-5515 3135);
DISPLAY 0.659574 (-5515 3135);
PAINT MONO (-5515 3135);
DISPLAY INVISIBLE (-5515 3135);
FORCEPROP 1 LASTPIN (-5525 3125) BN 12
J 2
(-5513 3133);
DISPLAY 0.617021 (-5513 3133);
PAINT GREEN (-5513 3133);
FORCEPROP 2 LAST CDS_LIB mstr_standard
J 0
(-5575 3125);
PAINT MONO (-5575 3125);
DISPLAY INVISIBLE (-5575 3125);
FORCEPROP 1 LAST BODY_TYPE PLUMBING
J 2
(-5575 3175);
DISPLAY 1.446809 (-5575 3175);
PAINT GREEN (-5575 3175);
DISPLAY INVISIBLE (-5575 3175);
FORCEPROP 1 LAST HDL_TAP TRUE
J 2
(-5900 3000);
DISPLAY 1.446809 (-5900 3000);
PAINT GREEN (-5900 3000);
DISPLAY INVISIBLE (-5900 3000);
FORCEPROP 1 LAST PATH I27
J 2
(-5573 3125);
DISPLAY 0.872340 (-5573 3125);
PAINT GREEN (-5573 3125);
DISPLAY INVISIBLE (-5573 3125);
FORCEADD TAP..1
R 2
(-5575 3225);
FORCEPROP 3 LASTPIN (-5525 3225) SIG_NAME TP_P3E_CPU1_PE2_RSR_RXN<14>
J 0
(-5515 3235);
DISPLAY 0.659574 (-5515 3235);
PAINT MONO (-5515 3235);
DISPLAY INVISIBLE (-5515 3235);
FORCEPROP 1 LASTPIN (-5525 3225) BN 14
J 2
(-5513 3233);
DISPLAY 0.617021 (-5513 3233);
PAINT GREEN (-5513 3233);
FORCEPROP 2 LAST CDS_LIB mstr_standard
J 0
(-5575 3225);
PAINT MONO (-5575 3225);
DISPLAY INVISIBLE (-5575 3225);
FORCEPROP 1 LAST BODY_TYPE PLUMBING
J 2
(-5575 3275);
DISPLAY 1.446809 (-5575 3275);
PAINT GREEN (-5575 3275);
DISPLAY INVISIBLE (-5575 3275);
FORCEPROP 1 LAST HDL_TAP TRUE
J 2
(-5900 3100);
DISPLAY 1.446809 (-5900 3100);
PAINT GREEN (-5900 3100);
DISPLAY INVISIBLE (-5900 3100);
FORCEPROP 1 LAST PATH I28
J 2
(-5573 3225);
DISPLAY 0.872340 (-5573 3225);
PAINT GREEN (-5573 3225);
DISPLAY INVISIBLE (-5573 3225);
FORCEADD TAP..1
R 2
(-5575 3175);
FORCEPROP 3 LASTPIN (-5525 3175) SIG_NAME TP_P3E_CPU1_PE2_RSR_RXN<13>
J 0
(-5515 3185);
DISPLAY 0.659574 (-5515 3185);
PAINT MONO (-5515 3185);
DISPLAY INVISIBLE (-5515 3185);
FORCEPROP 1 LASTPIN (-5525 3175) BN 13
J 2
(-5513 3183);
DISPLAY 0.617021 (-5513 3183);
PAINT GREEN (-5513 3183);
FORCEPROP 2 LAST CDS_LIB mstr_standard
J 0
(-5575 3175);
PAINT MONO (-5575 3175);
DISPLAY INVISIBLE (-5575 3175);
FORCEPROP 1 LAST BODY_TYPE PLUMBING
J 2
(-5575 3225);
DISPLAY 1.446809 (-5575 3225);
PAINT GREEN (-5575 3225);
DISPLAY INVISIBLE (-5575 3225);
FORCEPROP 1 LAST HDL_TAP TRUE
J 2
(-5900 3050);
DISPLAY 1.446809 (-5900 3050);
PAINT GREEN (-5900 3050);
DISPLAY INVISIBLE (-5900 3050);
FORCEPROP 1 LAST PATH I29
J 2
(-5573 3175);
DISPLAY 0.872340 (-5573 3175);
PAINT GREEN (-5573 3175);
DISPLAY INVISIBLE (-5573 3175);
FORCEADD TAP..1
R 2
(-5575 1725);
FORCEPROP 3 LASTPIN (-5525 1725) SIG_NAME TP_P3E_CPU1_PE2_RSR_RXN<2>
J 0
(-5515 1735);
DISPLAY 0.659574 (-5515 1735);
PAINT MONO (-5515 1735);
DISPLAY INVISIBLE (-5515 1735);
FORCEPROP 1 LASTPIN (-5525 1725) BN 2
J 2
(-5513 1733);
DISPLAY 0.617021 (-5513 1733);
PAINT GREEN (-5513 1733);
FORCEPROP 2 LAST CDS_LIB mstr_standard
J 0
(-5575 1725);
PAINT MONO (-5575 1725);
DISPLAY INVISIBLE (-5575 1725);
FORCEPROP 1 LAST BODY_TYPE PLUMBING
J 2
(-5575 1775);
DISPLAY 1.446809 (-5575 1775);
PAINT GREEN (-5575 1775);
DISPLAY INVISIBLE (-5575 1775);
FORCEPROP 1 LAST HDL_TAP TRUE
J 2
(-5900 1600);
DISPLAY 1.446809 (-5900 1600);
PAINT GREEN (-5900 1600);
DISPLAY INVISIBLE (-5900 1600);
FORCEPROP 1 LAST PATH I3
J 2
(-5573 1725);
DISPLAY 0.872340 (-5573 1725);
PAINT GREEN (-5573 1725);
DISPLAY INVISIBLE (-5573 1725);
FORCEADD TAP..1
R 2
(-5575 3275);
FORCEPROP 3 LASTPIN (-5525 3275) SIG_NAME TP_P3E_CPU1_PE2_RSR_RXN<15>
J 0
(-5515 3285);
DISPLAY 0.659574 (-5515 3285);
PAINT MONO (-5515 3285);
DISPLAY INVISIBLE (-5515 3285);
FORCEPROP 1 LASTPIN (-5525 3275) BN 15
J 2
(-5513 3283);
DISPLAY 0.617021 (-5513 3283);
PAINT GREEN (-5513 3283);
FORCEPROP 2 LAST CDS_LIB mstr_standard
J 0
(-5575 3275);
PAINT MONO (-5575 3275);
DISPLAY INVISIBLE (-5575 3275);
FORCEPROP 1 LAST BODY_TYPE PLUMBING
J 2
(-5575 3325);
DISPLAY 1.446809 (-5575 3325);
PAINT GREEN (-5575 3325);
DISPLAY INVISIBLE (-5575 3325);
FORCEPROP 1 LAST HDL_TAP TRUE
J 2
(-5900 3150);
DISPLAY 1.446809 (-5900 3150);
PAINT GREEN (-5900 3150);
DISPLAY INVISIBLE (-5900 3150);
FORCEPROP 1 LAST PATH I30
J 2
(-5573 3275);
DISPLAY 0.872340 (-5573 3275);
PAINT GREEN (-5573 3275);
DISPLAY INVISIBLE (-5573 3275);
FORCEADD TAP..1
R 2
(-5425 3025);
FORCEPROP 3 LASTPIN (-5375 3025) SIG_NAME TP_P3E_CPU1_PE2_RSR_RXP<11>
J 0
(-5365 3035);
DISPLAY 0.659574 (-5365 3035);
PAINT MONO (-5365 3035);
DISPLAY INVISIBLE (-5365 3035);
FORCEPROP 1 LASTPIN (-5375 3025) BN 11
J 2
(-5363 3033);
DISPLAY 0.617021 (-5363 3033);
PAINT GREEN (-5363 3033);
FORCEPROP 2 LAST CDS_LIB mstr_standard
J 0
(-5425 3025);
PAINT MONO (-5425 3025);
DISPLAY INVISIBLE (-5425 3025);
FORCEPROP 1 LAST BODY_TYPE PLUMBING
J 2
(-5425 3075);
DISPLAY 1.446809 (-5425 3075);
PAINT GREEN (-5425 3075);
DISPLAY INVISIBLE (-5425 3075);
FORCEPROP 1 LAST HDL_TAP TRUE
J 2
(-5750 2900);
DISPLAY 1.446809 (-5750 2900);
PAINT GREEN (-5750 2900);
DISPLAY INVISIBLE (-5750 2900);
FORCEPROP 1 LAST PATH I31
J 2
(-5423 3025);
DISPLAY 0.872340 (-5423 3025);
PAINT GREEN (-5423 3025);
DISPLAY INVISIBLE (-5423 3025);
FORCEADD TAP..1
R 2
(-5425 3375);
FORCEPROP 3 LASTPIN (-5375 3375) SIG_NAME TP_P3E_CPU1_PE2_RSR_RXP<12>
J 0
(-5365 3385);
DISPLAY 0.659574 (-5365 3385);
PAINT MONO (-5365 3385);
DISPLAY INVISIBLE (-5365 3385);
FORCEPROP 1 LASTPIN (-5375 3375) BN 12
J 2
(-5363 3383);
DISPLAY 0.617021 (-5363 3383);
PAINT GREEN (-5363 3383);
FORCEPROP 2 LAST CDS_LIB mstr_standard
J 0
(-5425 3375);
PAINT MONO (-5425 3375);
DISPLAY INVISIBLE (-5425 3375);
FORCEPROP 1 LAST BODY_TYPE PLUMBING
J 2
(-5425 3425);
DISPLAY 1.446809 (-5425 3425);
PAINT GREEN (-5425 3425);
DISPLAY INVISIBLE (-5425 3425);
FORCEPROP 1 LAST HDL_TAP TRUE
J 2
(-5750 3250);
DISPLAY 1.446809 (-5750 3250);
PAINT GREEN (-5750 3250);
DISPLAY INVISIBLE (-5750 3250);
FORCEPROP 1 LAST PATH I32
J 2
(-5423 3375);
DISPLAY 0.872340 (-5423 3375);
PAINT GREEN (-5423 3375);
DISPLAY INVISIBLE (-5423 3375);
FORCEADD TAP..1
R 2
(-5425 3475);
FORCEPROP 3 LASTPIN (-5375 3475) SIG_NAME TP_P3E_CPU1_PE2_RSR_RXP<14>
J 0
(-5365 3485);
DISPLAY 0.659574 (-5365 3485);
PAINT MONO (-5365 3485);
DISPLAY INVISIBLE (-5365 3485);
FORCEPROP 1 LASTPIN (-5375 3475) BN 14
J 2
(-5363 3483);
DISPLAY 0.617021 (-5363 3483);
PAINT GREEN (-5363 3483);
FORCEPROP 2 LAST CDS_LIB mstr_standard
J 0
(-5425 3475);
PAINT MONO (-5425 3475);
DISPLAY INVISIBLE (-5425 3475);
FORCEPROP 1 LAST BODY_TYPE PLUMBING
J 2
(-5425 3525);
DISPLAY 1.446809 (-5425 3525);
PAINT GREEN (-5425 3525);
DISPLAY INVISIBLE (-5425 3525);
FORCEPROP 1 LAST HDL_TAP TRUE
J 2
(-5750 3350);
DISPLAY 1.446809 (-5750 3350);
PAINT GREEN (-5750 3350);
DISPLAY INVISIBLE (-5750 3350);
FORCEPROP 1 LAST PATH I33
J 2
(-5423 3475);
DISPLAY 0.872340 (-5423 3475);
PAINT GREEN (-5423 3475);
DISPLAY INVISIBLE (-5423 3475);
FORCEADD TAP..1
R 2
(-5425 3425);
FORCEPROP 3 LASTPIN (-5375 3425) SIG_NAME TP_P3E_CPU1_PE2_RSR_RXP<13>
J 0
(-5365 3435);
DISPLAY 0.659574 (-5365 3435);
PAINT MONO (-5365 3435);
DISPLAY INVISIBLE (-5365 3435);
FORCEPROP 1 LASTPIN (-5375 3425) BN 13
J 2
(-5363 3433);
DISPLAY 0.617021 (-5363 3433);
PAINT GREEN (-5363 3433);
FORCEPROP 2 LAST CDS_LIB mstr_standard
J 0
(-5425 3425);
PAINT MONO (-5425 3425);
DISPLAY INVISIBLE (-5425 3425);
FORCEPROP 1 LAST BODY_TYPE PLUMBING
J 2
(-5425 3475);
DISPLAY 1.446809 (-5425 3475);
PAINT GREEN (-5425 3475);
DISPLAY INVISIBLE (-5425 3475);
FORCEPROP 1 LAST HDL_TAP TRUE
J 2
(-5750 3300);
DISPLAY 1.446809 (-5750 3300);
PAINT GREEN (-5750 3300);
DISPLAY INVISIBLE (-5750 3300);
FORCEPROP 1 LAST PATH I34
J 2
(-5423 3425);
DISPLAY 0.872340 (-5423 3425);
PAINT GREEN (-5423 3425);
DISPLAY INVISIBLE (-5423 3425);
FORCEADD TAP..1
R 2
(-5425 3525);
FORCEPROP 3 LASTPIN (-5375 3525) SIG_NAME TP_P3E_CPU1_PE2_RSR_RXP<15>
J 0
(-5365 3535);
DISPLAY 0.659574 (-5365 3535);
PAINT MONO (-5365 3535);
DISPLAY INVISIBLE (-5365 3535);
FORCEPROP 1 LASTPIN (-5375 3525) BN 15
J 2
(-5363 3533);
DISPLAY 0.617021 (-5363 3533);
PAINT GREEN (-5363 3533);
FORCEPROP 2 LAST CDS_LIB mstr_standard
J 0
(-5425 3525);
PAINT MONO (-5425 3525);
DISPLAY INVISIBLE (-5425 3525);
FORCEPROP 1 LAST BODY_TYPE PLUMBING
J 2
(-5425 3575);
DISPLAY 1.446809 (-5425 3575);
PAINT GREEN (-5425 3575);
DISPLAY INVISIBLE (-5425 3575);
FORCEPROP 1 LAST HDL_TAP TRUE
J 2
(-5750 3400);
DISPLAY 1.446809 (-5750 3400);
PAINT GREEN (-5750 3400);
DISPLAY INVISIBLE (-5750 3400);
FORCEPROP 1 LAST PATH I35
J 2
(-5423 3525);
DISPLAY 0.872340 (-5423 3525);
PAINT GREEN (-5423 3525);
DISPLAY INVISIBLE (-5423 3525);
FORCEADD TAP..1
(-2950 1975);
FORCEPROP 3 LASTPIN (-3000 1975) SIG_NAME TP_P3E_CPU1_PE2_RSR_TXP<2>
J 0
(-2990 1985);
DISPLAY 0.659574 (-2990 1985);
PAINT MONO (-2990 1985);
DISPLAY INVISIBLE (-2990 1985);
FORCEPROP 1 LASTPIN (-3000 1975) BN 2
J 0
(-3012 1983);
DISPLAY 0.617021 (-3012 1983);
PAINT GREEN (-3012 1983);
FORCEPROP 2 LAST CDS_LIB mstr_standard
J 2
(-2950 1975);
PAINT MONO (-2950 1975);
DISPLAY INVISIBLE (-2950 1975);
FORCEPROP 1 LAST BODY_TYPE PLUMBING
J 0
(-2950 2025);
DISPLAY 1.446809 (-2950 2025);
PAINT GREEN (-2950 2025);
DISPLAY INVISIBLE (-2950 2025);
FORCEPROP 1 LAST HDL_TAP TRUE
J 0
(-2625 1850);
DISPLAY 1.446809 (-2625 1850);
PAINT GREEN (-2625 1850);
DISPLAY INVISIBLE (-2625 1850);
FORCEPROP 1 LAST PATH I36
J 0
(-2952 1975);
DISPLAY 0.872340 (-2952 1975);
PAINT GREEN (-2952 1975);
DISPLAY INVISIBLE (-2952 1975);
FORCEADD TAP..1
(-2950 1875);
FORCEPROP 3 LASTPIN (-3000 1875) SIG_NAME TP_P3E_CPU1_PE2_RSR_TXP<0>
J 0
(-2990 1885);
DISPLAY 0.659574 (-2990 1885);
PAINT MONO (-2990 1885);
DISPLAY INVISIBLE (-2990 1885);
FORCEPROP 1 LASTPIN (-3000 1875) BN 0
J 0
(-3012 1883);
DISPLAY 0.617021 (-3012 1883);
PAINT GREEN (-3012 1883);
FORCEPROP 2 LAST CDS_LIB mstr_standard
J 2
(-2950 1875);
PAINT MONO (-2950 1875);
DISPLAY INVISIBLE (-2950 1875);
FORCEPROP 1 LAST BODY_TYPE PLUMBING
J 0
(-2950 1925);
DISPLAY 1.446809 (-2950 1925);
PAINT GREEN (-2950 1925);
DISPLAY INVISIBLE (-2950 1925);
FORCEPROP 1 LAST HDL_TAP TRUE
J 0
(-2625 1750);
DISPLAY 1.446809 (-2625 1750);
PAINT GREEN (-2625 1750);
DISPLAY INVISIBLE (-2625 1750);
FORCEPROP 1 LAST PATH I37
J 0
(-2952 1875);
DISPLAY 0.872340 (-2952 1875);
PAINT GREEN (-2952 1875);
DISPLAY INVISIBLE (-2952 1875);
FORCEADD TAP..1
(-2950 1925);
FORCEPROP 3 LASTPIN (-3000 1925) SIG_NAME TP_P3E_CPU1_PE2_RSR_TXP<1>
J 0
(-2990 1935);
DISPLAY 0.659574 (-2990 1935);
PAINT MONO (-2990 1935);
DISPLAY INVISIBLE (-2990 1935);
FORCEPROP 1 LASTPIN (-3000 1925) BN 1
J 0
(-3012 1933);
DISPLAY 0.617021 (-3012 1933);
PAINT GREEN (-3012 1933);
FORCEPROP 2 LAST CDS_LIB mstr_standard
J 2
(-2950 1925);
PAINT MONO (-2950 1925);
DISPLAY INVISIBLE (-2950 1925);
FORCEPROP 1 LAST BODY_TYPE PLUMBING
J 0
(-2950 1975);
DISPLAY 1.446809 (-2950 1975);
PAINT GREEN (-2950 1975);
DISPLAY INVISIBLE (-2950 1975);
FORCEPROP 1 LAST HDL_TAP TRUE
J 0
(-2625 1800);
DISPLAY 1.446809 (-2625 1800);
PAINT GREEN (-2625 1800);
DISPLAY INVISIBLE (-2625 1800);
FORCEPROP 1 LAST PATH I38
J 0
(-2952 1925);
DISPLAY 0.872340 (-2952 1925);
PAINT GREEN (-2952 1925);
DISPLAY INVISIBLE (-2952 1925);
FORCEADD TAP..1
(-2800 1675);
FORCEPROP 3 LASTPIN (-2850 1675) SIG_NAME TP_P3E_CPU1_PE2_RSR_TXN<1>
J 0
(-2840 1685);
DISPLAY 0.659574 (-2840 1685);
PAINT MONO (-2840 1685);
DISPLAY INVISIBLE (-2840 1685);
FORCEPROP 1 LASTPIN (-2850 1675) BN 1
J 0
(-2862 1683);
DISPLAY 0.617021 (-2862 1683);
PAINT GREEN (-2862 1683);
FORCEPROP 2 LAST CDS_LIB mstr_standard
J 2
(-2800 1675);
PAINT MONO (-2800 1675);
DISPLAY INVISIBLE (-2800 1675);
FORCEPROP 1 LAST BODY_TYPE PLUMBING
J 0
(-2800 1725);
DISPLAY 1.446809 (-2800 1725);
PAINT GREEN (-2800 1725);
DISPLAY INVISIBLE (-2800 1725);
FORCEPROP 1 LAST HDL_TAP TRUE
J 0
(-2475 1550);
DISPLAY 1.446809 (-2475 1550);
PAINT GREEN (-2475 1550);
DISPLAY INVISIBLE (-2475 1550);
FORCEPROP 1 LAST PATH I39
J 0
(-2802 1675);
DISPLAY 0.872340 (-2802 1675);
PAINT GREEN (-2802 1675);
DISPLAY INVISIBLE (-2802 1675);
FORCEADD TAP..1
R 2
(-5575 1675);
FORCEPROP 3 LASTPIN (-5525 1675) SIG_NAME TP_P3E_CPU1_PE2_RSR_RXN<1>
J 0
(-5515 1685);
DISPLAY 0.659574 (-5515 1685);
PAINT MONO (-5515 1685);
DISPLAY INVISIBLE (-5515 1685);
FORCEPROP 1 LASTPIN (-5525 1675) BN 1
J 2
(-5513 1683);
DISPLAY 0.617021 (-5513 1683);
PAINT GREEN (-5513 1683);
FORCEPROP 2 LAST CDS_LIB mstr_standard
J 0
(-5575 1675);
PAINT MONO (-5575 1675);
DISPLAY INVISIBLE (-5575 1675);
FORCEPROP 1 LAST BODY_TYPE PLUMBING
J 2
(-5575 1725);
DISPLAY 1.446809 (-5575 1725);
PAINT GREEN (-5575 1725);
DISPLAY INVISIBLE (-5575 1725);
FORCEPROP 1 LAST HDL_TAP TRUE
J 2
(-5900 1550);
DISPLAY 1.446809 (-5900 1550);
PAINT GREEN (-5900 1550);
DISPLAY INVISIBLE (-5900 1550);
FORCEPROP 1 LAST PATH I4
J 2
(-5573 1675);
DISPLAY 0.872340 (-5573 1675);
PAINT GREEN (-5573 1675);
DISPLAY INVISIBLE (-5573 1675);
FORCEADD TAP..1
(-2800 1625);
FORCEPROP 3 LASTPIN (-2850 1625) SIG_NAME TP_P3E_CPU1_PE2_RSR_TXN<0>
J 0
(-2840 1635);
DISPLAY 0.659574 (-2840 1635);
PAINT MONO (-2840 1635);
DISPLAY INVISIBLE (-2840 1635);
FORCEPROP 1 LASTPIN (-2850 1625) BN 0
J 0
(-2862 1633);
DISPLAY 0.617021 (-2862 1633);
PAINT GREEN (-2862 1633);
FORCEPROP 2 LAST CDS_LIB mstr_standard
J 2
(-2800 1625);
PAINT MONO (-2800 1625);
DISPLAY INVISIBLE (-2800 1625);
FORCEPROP 1 LAST BODY_TYPE PLUMBING
J 0
(-2800 1675);
DISPLAY 1.446809 (-2800 1675);
PAINT GREEN (-2800 1675);
DISPLAY INVISIBLE (-2800 1675);
FORCEPROP 1 LAST HDL_TAP TRUE
J 0
(-2475 1500);
DISPLAY 1.446809 (-2475 1500);
PAINT GREEN (-2475 1500);
DISPLAY INVISIBLE (-2475 1500);
FORCEPROP 1 LAST PATH I40
J 0
(-2802 1625);
DISPLAY 0.872340 (-2802 1625);
PAINT GREEN (-2802 1625);
DISPLAY INVISIBLE (-2802 1625);
FORCEADD TAP..1
(-2800 1725);
FORCEPROP 3 LASTPIN (-2850 1725) SIG_NAME TP_P3E_CPU1_PE2_RSR_TXN<2>
J 0
(-2840 1735);
DISPLAY 0.659574 (-2840 1735);
PAINT MONO (-2840 1735);
DISPLAY INVISIBLE (-2840 1735);
FORCEPROP 1 LASTPIN (-2850 1725) BN 2
J 0
(-2862 1733);
DISPLAY 0.617021 (-2862 1733);
PAINT GREEN (-2862 1733);
FORCEPROP 2 LAST CDS_LIB mstr_standard
J 2
(-2800 1725);
PAINT MONO (-2800 1725);
DISPLAY INVISIBLE (-2800 1725);
FORCEPROP 1 LAST BODY_TYPE PLUMBING
J 0
(-2800 1775);
DISPLAY 1.446809 (-2800 1775);
PAINT GREEN (-2800 1775);
DISPLAY INVISIBLE (-2800 1775);
FORCEPROP 1 LAST HDL_TAP TRUE
J 0
(-2475 1600);
DISPLAY 1.446809 (-2475 1600);
PAINT GREEN (-2475 1600);
DISPLAY INVISIBLE (-2475 1600);
FORCEPROP 1 LAST PATH I41
J 0
(-2802 1725);
DISPLAY 0.872340 (-2802 1725);
PAINT GREEN (-2802 1725);
DISPLAY INVISIBLE (-2802 1725);
FORCEADD TAP..1
(-2800 1775);
FORCEPROP 3 LASTPIN (-2850 1775) SIG_NAME TP_P3E_CPU1_PE2_RSR_TXN<3>
J 0
(-2840 1785);
DISPLAY 0.659574 (-2840 1785);
PAINT MONO (-2840 1785);
DISPLAY INVISIBLE (-2840 1785);
FORCEPROP 1 LASTPIN (-2850 1775) BN 3
J 0
(-2862 1783);
DISPLAY 0.617021 (-2862 1783);
PAINT GREEN (-2862 1783);
FORCEPROP 2 LAST CDS_LIB mstr_standard
J 2
(-2800 1775);
PAINT MONO (-2800 1775);
DISPLAY INVISIBLE (-2800 1775);
FORCEPROP 1 LAST BODY_TYPE PLUMBING
J 0
(-2800 1825);
DISPLAY 1.446809 (-2800 1825);
PAINT GREEN (-2800 1825);
DISPLAY INVISIBLE (-2800 1825);
FORCEPROP 1 LAST HDL_TAP TRUE
J 0
(-2475 1650);
DISPLAY 1.446809 (-2475 1650);
PAINT GREEN (-2475 1650);
DISPLAY INVISIBLE (-2475 1650);
FORCEPROP 1 LAST PATH I42
J 0
(-2802 1775);
DISPLAY 0.872340 (-2802 1775);
PAINT GREEN (-2802 1775);
DISPLAY INVISIBLE (-2802 1775);
FORCEADD TAP..1
(-2950 2475);
FORCEPROP 3 LASTPIN (-3000 2475) SIG_NAME TP_P3E_CPU1_PE2_RSR_TXP<6>
J 0
(-2990 2485);
DISPLAY 0.659574 (-2990 2485);
PAINT MONO (-2990 2485);
DISPLAY INVISIBLE (-2990 2485);
FORCEPROP 1 LASTPIN (-3000 2475) BN 6
J 0
(-3012 2483);
DISPLAY 0.617021 (-3012 2483);
PAINT GREEN (-3012 2483);
FORCEPROP 2 LAST CDS_LIB mstr_standard
J 2
(-2950 2475);
PAINT MONO (-2950 2475);
DISPLAY INVISIBLE (-2950 2475);
FORCEPROP 1 LAST BODY_TYPE PLUMBING
J 0
(-2950 2525);
DISPLAY 1.446809 (-2950 2525);
PAINT GREEN (-2950 2525);
DISPLAY INVISIBLE (-2950 2525);
FORCEPROP 1 LAST HDL_TAP TRUE
J 0
(-2625 2350);
DISPLAY 1.446809 (-2625 2350);
PAINT GREEN (-2625 2350);
DISPLAY INVISIBLE (-2625 2350);
FORCEPROP 1 LAST PATH I43
J 0
(-2952 2475);
DISPLAY 0.872340 (-2952 2475);
PAINT GREEN (-2952 2475);
DISPLAY INVISIBLE (-2952 2475);
FORCEADD TAP..1
(-2950 2425);
FORCEPROP 3 LASTPIN (-3000 2425) SIG_NAME TP_P3E_CPU1_PE2_RSR_TXP<5>
J 0
(-2990 2435);
DISPLAY 0.659574 (-2990 2435);
PAINT MONO (-2990 2435);
DISPLAY INVISIBLE (-2990 2435);
FORCEPROP 1 LASTPIN (-3000 2425) BN 5
J 0
(-3012 2433);
DISPLAY 0.617021 (-3012 2433);
PAINT GREEN (-3012 2433);
FORCEPROP 2 LAST CDS_LIB mstr_standard
J 2
(-2950 2425);
PAINT MONO (-2950 2425);
DISPLAY INVISIBLE (-2950 2425);
FORCEPROP 1 LAST BODY_TYPE PLUMBING
J 0
(-2950 2475);
DISPLAY 1.446809 (-2950 2475);
PAINT GREEN (-2950 2475);
DISPLAY INVISIBLE (-2950 2475);
FORCEPROP 1 LAST HDL_TAP TRUE
J 0
(-2625 2300);
DISPLAY 1.446809 (-2625 2300);
PAINT GREEN (-2625 2300);
DISPLAY INVISIBLE (-2625 2300);
FORCEPROP 1 LAST PATH I44
J 0
(-2952 2425);
DISPLAY 0.872340 (-2952 2425);
PAINT GREEN (-2952 2425);
DISPLAY INVISIBLE (-2952 2425);
FORCEADD TAP..1
(-2950 2375);
FORCEPROP 3 LASTPIN (-3000 2375) SIG_NAME TP_P3E_CPU1_PE2_RSR_TXP<4>
J 0
(-2990 2385);
DISPLAY 0.659574 (-2990 2385);
PAINT MONO (-2990 2385);
DISPLAY INVISIBLE (-2990 2385);
FORCEPROP 1 LASTPIN (-3000 2375) BN 4
J 0
(-3012 2383);
DISPLAY 0.617021 (-3012 2383);
PAINT GREEN (-3012 2383);
FORCEPROP 2 LAST CDS_LIB mstr_standard
J 2
(-2950 2375);
PAINT MONO (-2950 2375);
DISPLAY INVISIBLE (-2950 2375);
FORCEPROP 1 LAST BODY_TYPE PLUMBING
J 0
(-2950 2425);
DISPLAY 1.446809 (-2950 2425);
PAINT GREEN (-2950 2425);
DISPLAY INVISIBLE (-2950 2425);
FORCEPROP 1 LAST HDL_TAP TRUE
J 0
(-2625 2250);
DISPLAY 1.446809 (-2625 2250);
PAINT GREEN (-2625 2250);
DISPLAY INVISIBLE (-2625 2250);
FORCEPROP 1 LAST PATH I45
J 0
(-2952 2375);
DISPLAY 0.872340 (-2952 2375);
PAINT GREEN (-2952 2375);
DISPLAY INVISIBLE (-2952 2375);
FORCEADD TAP..1
(-2950 2025);
FORCEPROP 3 LASTPIN (-3000 2025) SIG_NAME TP_P3E_CPU1_PE2_RSR_TXP<3>
J 0
(-2990 2035);
DISPLAY 0.659574 (-2990 2035);
PAINT MONO (-2990 2035);
DISPLAY INVISIBLE (-2990 2035);
FORCEPROP 1 LASTPIN (-3000 2025) BN 3
J 0
(-3012 2033);
DISPLAY 0.617021 (-3012 2033);
PAINT GREEN (-3012 2033);
FORCEPROP 2 LAST CDS_LIB mstr_standard
J 2
(-2950 2025);
PAINT MONO (-2950 2025);
DISPLAY INVISIBLE (-2950 2025);
FORCEPROP 1 LAST BODY_TYPE PLUMBING
J 0
(-2950 2075);
DISPLAY 1.446809 (-2950 2075);
PAINT GREEN (-2950 2075);
DISPLAY INVISIBLE (-2950 2075);
FORCEPROP 1 LAST HDL_TAP TRUE
J 0
(-2625 1900);
DISPLAY 1.446809 (-2625 1900);
PAINT GREEN (-2625 1900);
DISPLAY INVISIBLE (-2625 1900);
FORCEPROP 1 LAST PATH I46
J 0
(-2952 2025);
DISPLAY 0.872340 (-2952 2025);
PAINT GREEN (-2952 2025);
DISPLAY INVISIBLE (-2952 2025);
FORCEADD TAP..1
(-2800 2125);
FORCEPROP 3 LASTPIN (-2850 2125) SIG_NAME TP_P3E_CPU1_PE2_RSR_TXN<4>
J 0
(-2840 2135);
DISPLAY 0.659574 (-2840 2135);
PAINT MONO (-2840 2135);
DISPLAY INVISIBLE (-2840 2135);
FORCEPROP 1 LASTPIN (-2850 2125) BN 4
J 0
(-2862 2133);
DISPLAY 0.617021 (-2862 2133);
PAINT GREEN (-2862 2133);
FORCEPROP 2 LAST CDS_LIB mstr_standard
J 2
(-2800 2125);
PAINT MONO (-2800 2125);
DISPLAY INVISIBLE (-2800 2125);
FORCEPROP 1 LAST BODY_TYPE PLUMBING
J 0
(-2800 2175);
DISPLAY 1.446809 (-2800 2175);
PAINT GREEN (-2800 2175);
DISPLAY INVISIBLE (-2800 2175);
FORCEPROP 1 LAST HDL_TAP TRUE
J 0
(-2475 2000);
DISPLAY 1.446809 (-2475 2000);
PAINT GREEN (-2475 2000);
DISPLAY INVISIBLE (-2475 2000);
FORCEPROP 1 LAST PATH I47
J 0
(-2802 2125);
DISPLAY 0.872340 (-2802 2125);
PAINT GREEN (-2802 2125);
DISPLAY INVISIBLE (-2802 2125);
FORCEADD TAP..1
(-2800 2175);
FORCEPROP 3 LASTPIN (-2850 2175) SIG_NAME TP_P3E_CPU1_PE2_RSR_TXN<5>
J 0
(-2840 2185);
DISPLAY 0.659574 (-2840 2185);
PAINT MONO (-2840 2185);
DISPLAY INVISIBLE (-2840 2185);
FORCEPROP 1 LASTPIN (-2850 2175) BN 5
J 0
(-2862 2183);
DISPLAY 0.617021 (-2862 2183);
PAINT GREEN (-2862 2183);
FORCEPROP 2 LAST CDS_LIB mstr_standard
J 2
(-2800 2175);
PAINT MONO (-2800 2175);
DISPLAY INVISIBLE (-2800 2175);
FORCEPROP 1 LAST BODY_TYPE PLUMBING
J 0
(-2800 2225);
DISPLAY 1.446809 (-2800 2225);
PAINT GREEN (-2800 2225);
DISPLAY INVISIBLE (-2800 2225);
FORCEPROP 1 LAST HDL_TAP TRUE
J 0
(-2475 2050);
DISPLAY 1.446809 (-2475 2050);
PAINT GREEN (-2475 2050);
DISPLAY INVISIBLE (-2475 2050);
FORCEPROP 1 LAST PATH I48
J 0
(-2802 2175);
DISPLAY 0.872340 (-2802 2175);
PAINT GREEN (-2802 2175);
DISPLAY INVISIBLE (-2802 2175);
FORCEADD TAP..1
(-2800 2225);
FORCEPROP 3 LASTPIN (-2850 2225) SIG_NAME TP_P3E_CPU1_PE2_RSR_TXN<6>
J 0
(-2840 2235);
DISPLAY 0.659574 (-2840 2235);
PAINT MONO (-2840 2235);
DISPLAY INVISIBLE (-2840 2235);
FORCEPROP 1 LASTPIN (-2850 2225) BN 6
J 0
(-2862 2233);
DISPLAY 0.617021 (-2862 2233);
PAINT GREEN (-2862 2233);
FORCEPROP 2 LAST CDS_LIB mstr_standard
J 2
(-2800 2225);
PAINT MONO (-2800 2225);
DISPLAY INVISIBLE (-2800 2225);
FORCEPROP 1 LAST BODY_TYPE PLUMBING
J 0
(-2800 2275);
DISPLAY 1.446809 (-2800 2275);
PAINT GREEN (-2800 2275);
DISPLAY INVISIBLE (-2800 2275);
FORCEPROP 1 LAST HDL_TAP TRUE
J 0
(-2475 2100);
DISPLAY 1.446809 (-2475 2100);
PAINT GREEN (-2475 2100);
DISPLAY INVISIBLE (-2475 2100);
FORCEPROP 1 LAST PATH I49
J 0
(-2802 2225);
DISPLAY 0.872340 (-2802 2225);
PAINT GREEN (-2802 2225);
DISPLAY INVISIBLE (-2802 2225);
FORCEADD TAP..1
R 2
(-5575 1625);
FORCEPROP 3 LASTPIN (-5525 1625) SIG_NAME TP_P3E_CPU1_PE2_RSR_RXN<0>
J 0
(-5515 1635);
DISPLAY 0.659574 (-5515 1635);
PAINT MONO (-5515 1635);
DISPLAY INVISIBLE (-5515 1635);
FORCEPROP 1 LASTPIN (-5525 1625) BN 0
J 2
(-5513 1633);
DISPLAY 0.617021 (-5513 1633);
PAINT GREEN (-5513 1633);
FORCEPROP 2 LAST CDS_LIB mstr_standard
J 0
(-5575 1625);
PAINT MONO (-5575 1625);
DISPLAY INVISIBLE (-5575 1625);
FORCEPROP 1 LAST BODY_TYPE PLUMBING
J 2
(-5575 1675);
DISPLAY 1.446809 (-5575 1675);
PAINT GREEN (-5575 1675);
DISPLAY INVISIBLE (-5575 1675);
FORCEPROP 1 LAST HDL_TAP TRUE
J 2
(-5900 1500);
DISPLAY 1.446809 (-5900 1500);
PAINT GREEN (-5900 1500);
DISPLAY INVISIBLE (-5900 1500);
FORCEPROP 1 LAST PATH I5
J 2
(-5573 1625);
DISPLAY 0.872340 (-5573 1625);
PAINT GREEN (-5573 1625);
DISPLAY INVISIBLE (-5573 1625);
FORCEADD TAP..1
(-2800 2275);
FORCEPROP 3 LASTPIN (-2850 2275) SIG_NAME TP_P3E_CPU1_PE2_RSR_TXN<7>
J 0
(-2840 2285);
DISPLAY 0.659574 (-2840 2285);
PAINT MONO (-2840 2285);
DISPLAY INVISIBLE (-2840 2285);
FORCEPROP 1 LASTPIN (-2850 2275) BN 7
J 0
(-2862 2283);
DISPLAY 0.617021 (-2862 2283);
PAINT GREEN (-2862 2283);
FORCEPROP 2 LAST CDS_LIB mstr_standard
J 2
(-2800 2275);
PAINT MONO (-2800 2275);
DISPLAY INVISIBLE (-2800 2275);
FORCEPROP 1 LAST BODY_TYPE PLUMBING
J 0
(-2800 2325);
DISPLAY 1.446809 (-2800 2325);
PAINT GREEN (-2800 2325);
DISPLAY INVISIBLE (-2800 2325);
FORCEPROP 1 LAST HDL_TAP TRUE
J 0
(-2475 2150);
DISPLAY 1.446809 (-2475 2150);
PAINT GREEN (-2475 2150);
DISPLAY INVISIBLE (-2475 2150);
FORCEPROP 1 LAST PATH I50
J 0
(-2802 2275);
DISPLAY 0.872340 (-2802 2275);
PAINT GREEN (-2802 2275);
DISPLAY INVISIBLE (-2802 2275);
FORCEADD TAP..1
(-2950 2975);
FORCEPROP 3 LASTPIN (-3000 2975) SIG_NAME TP_P3E_CPU1_PE2_RSR_TXP<10>
J 0
(-2990 2985);
DISPLAY 0.659574 (-2990 2985);
PAINT MONO (-2990 2985);
DISPLAY INVISIBLE (-2990 2985);
FORCEPROP 1 LASTPIN (-3000 2975) BN 10
J 0
(-3012 2983);
DISPLAY 0.617021 (-3012 2983);
PAINT GREEN (-3012 2983);
FORCEPROP 2 LAST CDS_LIB mstr_standard
J 2
(-2950 2975);
PAINT MONO (-2950 2975);
DISPLAY INVISIBLE (-2950 2975);
FORCEPROP 1 LAST BODY_TYPE PLUMBING
J 0
(-2950 3025);
DISPLAY 1.446809 (-2950 3025);
PAINT GREEN (-2950 3025);
DISPLAY INVISIBLE (-2950 3025);
FORCEPROP 1 LAST HDL_TAP TRUE
J 0
(-2625 2850);
DISPLAY 1.446809 (-2625 2850);
PAINT GREEN (-2625 2850);
DISPLAY INVISIBLE (-2625 2850);
FORCEPROP 1 LAST PATH I51
J 0
(-2952 2975);
DISPLAY 0.872340 (-2952 2975);
PAINT GREEN (-2952 2975);
DISPLAY INVISIBLE (-2952 2975);
FORCEADD TAP..1
(-2950 2925);
FORCEPROP 3 LASTPIN (-3000 2925) SIG_NAME TP_P3E_CPU1_PE2_RSR_TXP<9>
J 0
(-2990 2935);
DISPLAY 0.659574 (-2990 2935);
PAINT MONO (-2990 2935);
DISPLAY INVISIBLE (-2990 2935);
FORCEPROP 1 LASTPIN (-3000 2925) BN 9
J 0
(-3012 2933);
DISPLAY 0.617021 (-3012 2933);
PAINT GREEN (-3012 2933);
FORCEPROP 2 LAST CDS_LIB mstr_standard
J 2
(-2950 2925);
PAINT MONO (-2950 2925);
DISPLAY INVISIBLE (-2950 2925);
FORCEPROP 1 LAST BODY_TYPE PLUMBING
J 0
(-2950 2975);
DISPLAY 1.446809 (-2950 2975);
PAINT GREEN (-2950 2975);
DISPLAY INVISIBLE (-2950 2975);
FORCEPROP 1 LAST HDL_TAP TRUE
J 0
(-2625 2800);
DISPLAY 1.446809 (-2625 2800);
PAINT GREEN (-2625 2800);
DISPLAY INVISIBLE (-2625 2800);
FORCEPROP 1 LAST PATH I52
J 0
(-2952 2925);
DISPLAY 0.872340 (-2952 2925);
PAINT GREEN (-2952 2925);
DISPLAY INVISIBLE (-2952 2925);
FORCEADD TAP..1
(-2950 2875);
FORCEPROP 3 LASTPIN (-3000 2875) SIG_NAME TP_P3E_CPU1_PE2_RSR_TXP<8>
J 0
(-2990 2885);
DISPLAY 0.659574 (-2990 2885);
PAINT MONO (-2990 2885);
DISPLAY INVISIBLE (-2990 2885);
FORCEPROP 1 LASTPIN (-3000 2875) BN 8
J 0
(-3012 2883);
DISPLAY 0.617021 (-3012 2883);
PAINT GREEN (-3012 2883);
FORCEPROP 2 LAST CDS_LIB mstr_standard
J 2
(-2950 2875);
PAINT MONO (-2950 2875);
DISPLAY INVISIBLE (-2950 2875);
FORCEPROP 1 LAST BODY_TYPE PLUMBING
J 0
(-2950 2925);
DISPLAY 1.446809 (-2950 2925);
PAINT GREEN (-2950 2925);
DISPLAY INVISIBLE (-2950 2925);
FORCEPROP 1 LAST HDL_TAP TRUE
J 0
(-2625 2750);
DISPLAY 1.446809 (-2625 2750);
PAINT GREEN (-2625 2750);
DISPLAY INVISIBLE (-2625 2750);
FORCEPROP 1 LAST PATH I53
J 0
(-2952 2875);
DISPLAY 0.872340 (-2952 2875);
PAINT GREEN (-2952 2875);
DISPLAY INVISIBLE (-2952 2875);
FORCEADD TAP..1
(-2950 2525);
FORCEPROP 3 LASTPIN (-3000 2525) SIG_NAME TP_P3E_CPU1_PE2_RSR_TXP<7>
J 0
(-2990 2535);
DISPLAY 0.659574 (-2990 2535);
PAINT MONO (-2990 2535);
DISPLAY INVISIBLE (-2990 2535);
FORCEPROP 1 LASTPIN (-3000 2525) BN 7
J 0
(-3012 2533);
DISPLAY 0.617021 (-3012 2533);
PAINT GREEN (-3012 2533);
FORCEPROP 2 LAST CDS_LIB mstr_standard
J 2
(-2950 2525);
PAINT MONO (-2950 2525);
DISPLAY INVISIBLE (-2950 2525);
FORCEPROP 1 LAST BODY_TYPE PLUMBING
J 0
(-2950 2575);
DISPLAY 1.446809 (-2950 2575);
PAINT GREEN (-2950 2575);
DISPLAY INVISIBLE (-2950 2575);
FORCEPROP 1 LAST HDL_TAP TRUE
J 0
(-2625 2400);
DISPLAY 1.446809 (-2625 2400);
PAINT GREEN (-2625 2400);
DISPLAY INVISIBLE (-2625 2400);
FORCEPROP 1 LAST PATH I54
J 0
(-2952 2525);
DISPLAY 0.872340 (-2952 2525);
PAINT GREEN (-2952 2525);
DISPLAY INVISIBLE (-2952 2525);
FORCEADD TAP..1
(-2800 2625);
FORCEPROP 3 LASTPIN (-2850 2625) SIG_NAME TP_P3E_CPU1_PE2_RSR_TXN<8>
J 0
(-2840 2635);
DISPLAY 0.659574 (-2840 2635);
PAINT MONO (-2840 2635);
DISPLAY INVISIBLE (-2840 2635);
FORCEPROP 1 LASTPIN (-2850 2625) BN 8
J 0
(-2862 2633);
DISPLAY 0.617021 (-2862 2633);
PAINT GREEN (-2862 2633);
FORCEPROP 2 LAST CDS_LIB mstr_standard
J 2
(-2800 2625);
PAINT MONO (-2800 2625);
DISPLAY INVISIBLE (-2800 2625);
FORCEPROP 1 LAST BODY_TYPE PLUMBING
J 0
(-2800 2675);
DISPLAY 1.446809 (-2800 2675);
PAINT GREEN (-2800 2675);
DISPLAY INVISIBLE (-2800 2675);
FORCEPROP 1 LAST HDL_TAP TRUE
J 0
(-2475 2500);
DISPLAY 1.446809 (-2475 2500);
PAINT GREEN (-2475 2500);
DISPLAY INVISIBLE (-2475 2500);
FORCEPROP 1 LAST PATH I55
J 0
(-2802 2625);
DISPLAY 0.872340 (-2802 2625);
PAINT GREEN (-2802 2625);
DISPLAY INVISIBLE (-2802 2625);
FORCEADD TAP..1
(-2800 2725);
FORCEPROP 3 LASTPIN (-2850 2725) SIG_NAME TP_P3E_CPU1_PE2_RSR_TXN<10>
J 0
(-2840 2735);
DISPLAY 0.659574 (-2840 2735);
PAINT MONO (-2840 2735);
DISPLAY INVISIBLE (-2840 2735);
FORCEPROP 1 LASTPIN (-2850 2725) BN 10
J 0
(-2862 2733);
DISPLAY 0.617021 (-2862 2733);
PAINT GREEN (-2862 2733);
FORCEPROP 2 LAST CDS_LIB mstr_standard
J 2
(-2800 2725);
PAINT MONO (-2800 2725);
DISPLAY INVISIBLE (-2800 2725);
FORCEPROP 1 LAST BODY_TYPE PLUMBING
J 0
(-2800 2775);
DISPLAY 1.446809 (-2800 2775);
PAINT GREEN (-2800 2775);
DISPLAY INVISIBLE (-2800 2775);
FORCEPROP 1 LAST HDL_TAP TRUE
J 0
(-2475 2600);
DISPLAY 1.446809 (-2475 2600);
PAINT GREEN (-2475 2600);
DISPLAY INVISIBLE (-2475 2600);
FORCEPROP 1 LAST PATH I56
J 0
(-2802 2725);
DISPLAY 0.872340 (-2802 2725);
PAINT GREEN (-2802 2725);
DISPLAY INVISIBLE (-2802 2725);
FORCEADD TAP..1
(-2800 2675);
FORCEPROP 3 LASTPIN (-2850 2675) SIG_NAME TP_P3E_CPU1_PE2_RSR_TXN<9>
J 0
(-2840 2685);
DISPLAY 0.659574 (-2840 2685);
PAINT MONO (-2840 2685);
DISPLAY INVISIBLE (-2840 2685);
FORCEPROP 1 LASTPIN (-2850 2675) BN 9
J 0
(-2862 2683);
DISPLAY 0.617021 (-2862 2683);
PAINT GREEN (-2862 2683);
FORCEPROP 2 LAST CDS_LIB mstr_standard
J 2
(-2800 2675);
PAINT MONO (-2800 2675);
DISPLAY INVISIBLE (-2800 2675);
FORCEPROP 1 LAST BODY_TYPE PLUMBING
J 0
(-2800 2725);
DISPLAY 1.446809 (-2800 2725);
PAINT GREEN (-2800 2725);
DISPLAY INVISIBLE (-2800 2725);
FORCEPROP 1 LAST HDL_TAP TRUE
J 0
(-2475 2550);
DISPLAY 1.446809 (-2475 2550);
PAINT GREEN (-2475 2550);
DISPLAY INVISIBLE (-2475 2550);
FORCEPROP 1 LAST PATH I57
J 0
(-2802 2675);
DISPLAY 0.872340 (-2802 2675);
PAINT GREEN (-2802 2675);
DISPLAY INVISIBLE (-2802 2675);
FORCEADD TAP..1
(-2800 2775);
FORCEPROP 3 LASTPIN (-2850 2775) SIG_NAME TP_P3E_CPU1_PE2_RSR_TXN<11>
J 0
(-2840 2785);
DISPLAY 0.659574 (-2840 2785);
PAINT MONO (-2840 2785);
DISPLAY INVISIBLE (-2840 2785);
FORCEPROP 1 LASTPIN (-2850 2775) BN 11
J 0
(-2862 2783);
DISPLAY 0.617021 (-2862 2783);
PAINT GREEN (-2862 2783);
FORCEPROP 2 LAST CDS_LIB mstr_standard
J 2
(-2800 2775);
PAINT MONO (-2800 2775);
DISPLAY INVISIBLE (-2800 2775);
FORCEPROP 1 LAST BODY_TYPE PLUMBING
J 0
(-2800 2825);
DISPLAY 1.446809 (-2800 2825);
PAINT GREEN (-2800 2825);
DISPLAY INVISIBLE (-2800 2825);
FORCEPROP 1 LAST HDL_TAP TRUE
J 0
(-2475 2650);
DISPLAY 1.446809 (-2475 2650);
PAINT GREEN (-2475 2650);
DISPLAY INVISIBLE (-2475 2650);
FORCEPROP 1 LAST PATH I58
J 0
(-2802 2775);
DISPLAY 0.872340 (-2802 2775);
PAINT GREEN (-2802 2775);
DISPLAY INVISIBLE (-2802 2775);
FORCEADD TAP..1
(-2950 3525);
FORCEPROP 3 LASTPIN (-3000 3525) SIG_NAME TP_P3E_CPU1_PE2_RSR_TXP<15>
J 0
(-2990 3535);
DISPLAY 0.659574 (-2990 3535);
PAINT MONO (-2990 3535);
DISPLAY INVISIBLE (-2990 3535);
FORCEPROP 1 LASTPIN (-3000 3525) BN 15
J 0
(-3012 3533);
DISPLAY 0.617021 (-3012 3533);
PAINT GREEN (-3012 3533);
FORCEPROP 2 LAST CDS_LIB mstr_standard
J 2
(-2950 3525);
PAINT MONO (-2950 3525);
DISPLAY INVISIBLE (-2950 3525);
FORCEPROP 1 LAST BODY_TYPE PLUMBING
J 0
(-2950 3575);
DISPLAY 1.446809 (-2950 3575);
PAINT GREEN (-2950 3575);
DISPLAY INVISIBLE (-2950 3575);
FORCEPROP 1 LAST HDL_TAP TRUE
J 0
(-2625 3400);
DISPLAY 1.446809 (-2625 3400);
PAINT GREEN (-2625 3400);
DISPLAY INVISIBLE (-2625 3400);
FORCEPROP 1 LAST PATH I59
J 0
(-2952 3525);
DISPLAY 0.872340 (-2952 3525);
PAINT GREEN (-2952 3525);
DISPLAY INVISIBLE (-2952 3525);
FORCEADD TAP..1
R 2
(-5575 1775);
FORCEPROP 3 LASTPIN (-5525 1775) SIG_NAME TP_P3E_CPU1_PE2_RSR_RXN<3>
J 0
(-5515 1785);
DISPLAY 0.659574 (-5515 1785);
PAINT MONO (-5515 1785);
DISPLAY INVISIBLE (-5515 1785);
FORCEPROP 1 LASTPIN (-5525 1775) BN 3
J 2
(-5513 1783);
DISPLAY 0.617021 (-5513 1783);
PAINT GREEN (-5513 1783);
FORCEPROP 2 LAST CDS_LIB mstr_standard
J 0
(-5575 1775);
PAINT MONO (-5575 1775);
DISPLAY INVISIBLE (-5575 1775);
FORCEPROP 1 LAST BODY_TYPE PLUMBING
J 2
(-5575 1825);
DISPLAY 1.446809 (-5575 1825);
PAINT GREEN (-5575 1825);
DISPLAY INVISIBLE (-5575 1825);
FORCEPROP 1 LAST HDL_TAP TRUE
J 2
(-5900 1650);
DISPLAY 1.446809 (-5900 1650);
PAINT GREEN (-5900 1650);
DISPLAY INVISIBLE (-5900 1650);
FORCEPROP 1 LAST PATH I6
J 2
(-5573 1775);
DISPLAY 0.872340 (-5573 1775);
PAINT GREEN (-5573 1775);
DISPLAY INVISIBLE (-5573 1775);
FORCEADD TAP..1
(-2950 3475);
FORCEPROP 3 LASTPIN (-3000 3475) SIG_NAME TP_P3E_CPU1_PE2_RSR_TXP<14>
J 0
(-2990 3485);
DISPLAY 0.659574 (-2990 3485);
PAINT MONO (-2990 3485);
DISPLAY INVISIBLE (-2990 3485);
FORCEPROP 1 LASTPIN (-3000 3475) BN 14
J 0
(-3012 3483);
DISPLAY 0.617021 (-3012 3483);
PAINT GREEN (-3012 3483);
FORCEPROP 2 LAST CDS_LIB mstr_standard
J 2
(-2950 3475);
PAINT MONO (-2950 3475);
DISPLAY INVISIBLE (-2950 3475);
FORCEPROP 1 LAST BODY_TYPE PLUMBING
J 0
(-2950 3525);
DISPLAY 1.446809 (-2950 3525);
PAINT GREEN (-2950 3525);
DISPLAY INVISIBLE (-2950 3525);
FORCEPROP 1 LAST HDL_TAP TRUE
J 0
(-2625 3350);
DISPLAY 1.446809 (-2625 3350);
PAINT GREEN (-2625 3350);
DISPLAY INVISIBLE (-2625 3350);
FORCEPROP 1 LAST PATH I60
J 0
(-2952 3475);
DISPLAY 0.872340 (-2952 3475);
PAINT GREEN (-2952 3475);
DISPLAY INVISIBLE (-2952 3475);
FORCEADD TAP..1
(-2950 3425);
FORCEPROP 3 LASTPIN (-3000 3425) SIG_NAME TP_P3E_CPU1_PE2_RSR_TXP<13>
J 0
(-2990 3435);
DISPLAY 0.659574 (-2990 3435);
PAINT MONO (-2990 3435);
DISPLAY INVISIBLE (-2990 3435);
FORCEPROP 1 LASTPIN (-3000 3425) BN 13
J 0
(-3012 3433);
DISPLAY 0.617021 (-3012 3433);
PAINT GREEN (-3012 3433);
FORCEPROP 2 LAST CDS_LIB mstr_standard
J 2
(-2950 3425);
PAINT MONO (-2950 3425);
DISPLAY INVISIBLE (-2950 3425);
FORCEPROP 1 LAST BODY_TYPE PLUMBING
J 0
(-2950 3475);
DISPLAY 1.446809 (-2950 3475);
PAINT GREEN (-2950 3475);
DISPLAY INVISIBLE (-2950 3475);
FORCEPROP 1 LAST HDL_TAP TRUE
J 0
(-2625 3300);
DISPLAY 1.446809 (-2625 3300);
PAINT GREEN (-2625 3300);
DISPLAY INVISIBLE (-2625 3300);
FORCEPROP 1 LAST PATH I61
J 0
(-2952 3425);
DISPLAY 0.872340 (-2952 3425);
PAINT GREEN (-2952 3425);
DISPLAY INVISIBLE (-2952 3425);
FORCEADD TAP..1
(-2950 3375);
FORCEPROP 3 LASTPIN (-3000 3375) SIG_NAME TP_P3E_CPU1_PE2_RSR_TXP<12>
J 0
(-2990 3385);
DISPLAY 0.659574 (-2990 3385);
PAINT MONO (-2990 3385);
DISPLAY INVISIBLE (-2990 3385);
FORCEPROP 1 LASTPIN (-3000 3375) BN 12
J 0
(-3012 3383);
DISPLAY 0.617021 (-3012 3383);
PAINT GREEN (-3012 3383);
FORCEPROP 2 LAST CDS_LIB mstr_standard
J 2
(-2950 3375);
PAINT MONO (-2950 3375);
DISPLAY INVISIBLE (-2950 3375);
FORCEPROP 1 LAST BODY_TYPE PLUMBING
J 0
(-2950 3425);
DISPLAY 1.446809 (-2950 3425);
PAINT GREEN (-2950 3425);
DISPLAY INVISIBLE (-2950 3425);
FORCEPROP 1 LAST HDL_TAP TRUE
J 0
(-2625 3250);
DISPLAY 1.446809 (-2625 3250);
PAINT GREEN (-2625 3250);
DISPLAY INVISIBLE (-2625 3250);
FORCEPROP 1 LAST PATH I62
J 0
(-2952 3375);
DISPLAY 0.872340 (-2952 3375);
PAINT GREEN (-2952 3375);
DISPLAY INVISIBLE (-2952 3375);
FORCEADD TAP..1
(-2950 3025);
FORCEPROP 3 LASTPIN (-3000 3025) SIG_NAME TP_P3E_CPU1_PE2_RSR_TXP<11>
J 0
(-2990 3035);
DISPLAY 0.659574 (-2990 3035);
PAINT MONO (-2990 3035);
DISPLAY INVISIBLE (-2990 3035);
FORCEPROP 1 LASTPIN (-3000 3025) BN 11
J 0
(-3012 3033);
DISPLAY 0.617021 (-3012 3033);
PAINT GREEN (-3012 3033);
FORCEPROP 2 LAST CDS_LIB mstr_standard
J 2
(-2950 3025);
PAINT MONO (-2950 3025);
DISPLAY INVISIBLE (-2950 3025);
FORCEPROP 1 LAST BODY_TYPE PLUMBING
J 0
(-2950 3075);
DISPLAY 1.446809 (-2950 3075);
PAINT GREEN (-2950 3075);
DISPLAY INVISIBLE (-2950 3075);
FORCEPROP 1 LAST HDL_TAP TRUE
J 0
(-2625 2900);
DISPLAY 1.446809 (-2625 2900);
PAINT GREEN (-2625 2900);
DISPLAY INVISIBLE (-2625 2900);
FORCEPROP 1 LAST PATH I63
J 0
(-2952 3025);
DISPLAY 0.872340 (-2952 3025);
PAINT GREEN (-2952 3025);
DISPLAY INVISIBLE (-2952 3025);
FORCEADD TAP..1
(-2800 3125);
FORCEPROP 3 LASTPIN (-2850 3125) SIG_NAME TP_P3E_CPU1_PE2_RSR_TXN<12>
J 0
(-2840 3135);
DISPLAY 0.659574 (-2840 3135);
PAINT MONO (-2840 3135);
DISPLAY INVISIBLE (-2840 3135);
FORCEPROP 1 LASTPIN (-2850 3125) BN 12
J 0
(-2862 3133);
DISPLAY 0.617021 (-2862 3133);
PAINT GREEN (-2862 3133);
FORCEPROP 2 LAST CDS_LIB mstr_standard
J 2
(-2800 3125);
PAINT MONO (-2800 3125);
DISPLAY INVISIBLE (-2800 3125);
FORCEPROP 1 LAST BODY_TYPE PLUMBING
J 0
(-2800 3175);
DISPLAY 1.446809 (-2800 3175);
PAINT GREEN (-2800 3175);
DISPLAY INVISIBLE (-2800 3175);
FORCEPROP 1 LAST HDL_TAP TRUE
J 0
(-2475 3000);
DISPLAY 1.446809 (-2475 3000);
PAINT GREEN (-2475 3000);
DISPLAY INVISIBLE (-2475 3000);
FORCEPROP 1 LAST PATH I64
J 0
(-2802 3125);
DISPLAY 0.872340 (-2802 3125);
PAINT GREEN (-2802 3125);
DISPLAY INVISIBLE (-2802 3125);
FORCEADD TAP..1
(-2800 3175);
FORCEPROP 3 LASTPIN (-2850 3175) SIG_NAME TP_P3E_CPU1_PE2_RSR_TXN<13>
J 0
(-2840 3185);
DISPLAY 0.659574 (-2840 3185);
PAINT MONO (-2840 3185);
DISPLAY INVISIBLE (-2840 3185);
FORCEPROP 1 LASTPIN (-2850 3175) BN 13
J 0
(-2862 3183);
DISPLAY 0.617021 (-2862 3183);
PAINT GREEN (-2862 3183);
FORCEPROP 2 LAST CDS_LIB mstr_standard
J 2
(-2800 3175);
PAINT MONO (-2800 3175);
DISPLAY INVISIBLE (-2800 3175);
FORCEPROP 1 LAST BODY_TYPE PLUMBING
J 0
(-2800 3225);
DISPLAY 1.446809 (-2800 3225);
PAINT GREEN (-2800 3225);
DISPLAY INVISIBLE (-2800 3225);
FORCEPROP 1 LAST HDL_TAP TRUE
J 0
(-2475 3050);
DISPLAY 1.446809 (-2475 3050);
PAINT GREEN (-2475 3050);
DISPLAY INVISIBLE (-2475 3050);
FORCEPROP 1 LAST PATH I65
J 0
(-2802 3175);
DISPLAY 0.872340 (-2802 3175);
PAINT GREEN (-2802 3175);
DISPLAY INVISIBLE (-2802 3175);
FORCEADD TAP..1
(-2800 3275);
FORCEPROP 3 LASTPIN (-2850 3275) SIG_NAME TP_P3E_CPU1_PE2_RSR_TXN<15>
J 0
(-2840 3285);
DISPLAY 0.659574 (-2840 3285);
PAINT MONO (-2840 3285);
DISPLAY INVISIBLE (-2840 3285);
FORCEPROP 1 LASTPIN (-2850 3275) BN 15
J 0
(-2862 3283);
DISPLAY 0.617021 (-2862 3283);
PAINT GREEN (-2862 3283);
FORCEPROP 2 LAST CDS_LIB mstr_standard
J 2
(-2800 3275);
PAINT MONO (-2800 3275);
DISPLAY INVISIBLE (-2800 3275);
FORCEPROP 1 LAST BODY_TYPE PLUMBING
J 0
(-2800 3325);
DISPLAY 1.446809 (-2800 3325);
PAINT GREEN (-2800 3325);
DISPLAY INVISIBLE (-2800 3325);
FORCEPROP 1 LAST HDL_TAP TRUE
J 0
(-2475 3150);
DISPLAY 1.446809 (-2475 3150);
PAINT GREEN (-2475 3150);
DISPLAY INVISIBLE (-2475 3150);
FORCEPROP 1 LAST PATH I66
J 0
(-2802 3275);
DISPLAY 0.872340 (-2802 3275);
PAINT GREEN (-2802 3275);
DISPLAY INVISIBLE (-2802 3275);
FORCEADD TAP..1
(-2800 3225);
FORCEPROP 3 LASTPIN (-2850 3225) SIG_NAME TP_P3E_CPU1_PE2_RSR_TXN<14>
J 0
(-2840 3235);
DISPLAY 0.659574 (-2840 3235);
PAINT MONO (-2840 3235);
DISPLAY INVISIBLE (-2840 3235);
FORCEPROP 1 LASTPIN (-2850 3225) BN 14
J 0
(-2862 3233);
DISPLAY 0.617021 (-2862 3233);
PAINT GREEN (-2862 3233);
FORCEPROP 2 LAST CDS_LIB mstr_standard
J 2
(-2800 3225);
PAINT MONO (-2800 3225);
DISPLAY INVISIBLE (-2800 3225);
FORCEPROP 1 LAST BODY_TYPE PLUMBING
J 0
(-2800 3275);
DISPLAY 1.446809 (-2800 3275);
PAINT GREEN (-2800 3275);
DISPLAY INVISIBLE (-2800 3275);
FORCEPROP 1 LAST HDL_TAP TRUE
J 0
(-2475 3100);
DISPLAY 1.446809 (-2475 3100);
PAINT GREEN (-2475 3100);
DISPLAY INVISIBLE (-2475 3100);
FORCEPROP 1 LAST PATH I67
J 0
(-2802 3225);
DISPLAY 0.872340 (-2802 3225);
PAINT GREEN (-2802 3225);
DISPLAY INVISIBLE (-2802 3225);
FORCEADD SKX_EXT_B..11
(-4150 2575);
FORCEPROP 1 LAST LOCATION U2D1
J 0
(-4850 3775);
DISPLAY 0.617021 (-4850 3775);
PAINT AQUA (-4850 3775);
FORCEPROP 1 LAST PART_NUMBER TBD
J 0
(-4850 1425);
DISPLAY 0.617021 (-4850 1425);
PAINT BLUE (-4850 1425);
FORCEPROP 1 LAST MATERIAL IC
J 0
(-4850 3725);
DISPLAY 0.617021 (-4850 3725);
PAINT SKYBLUE (-4850 3725);
FORCEPROP 2 LASTPIN (-3400 3525) $PN BK5
J 0
(-3390 3535);
DISPLAY 0.617021 (-3390 3535);
PAINT ORANGE (-3390 3535);
FORCEPROP 2 LASTPIN (-3400 3475) $PN BM3
J 0
(-3390 3485);
DISPLAY 0.617021 (-3390 3485);
PAINT ORANGE (-3390 3485);
FORCEPROP 2 LASTPIN (-3400 3425) $PN BN4
J 0
(-3390 3435);
DISPLAY 0.617021 (-3390 3435);
PAINT ORANGE (-3390 3435);
FORCEPROP 2 LASTPIN (-3400 3375) $PN BR4
J 0
(-3390 3385);
DISPLAY 0.617021 (-3390 3385);
PAINT ORANGE (-3390 3385);
FORCEPROP 2 LASTPIN (-3400 3025) $PN BV3
J 0
(-3390 3035);
DISPLAY 0.617021 (-3390 3035);
PAINT ORANGE (-3390 3035);
FORCEPROP 2 LASTPIN (-3400 2975) $PN BY5
J 0
(-3390 2985);
DISPLAY 0.617021 (-3390 2985);
PAINT ORANGE (-3390 2985);
FORCEPROP 2 LASTPIN (-3400 2925) $PN BY3
J 0
(-3390 2935);
DISPLAY 0.617021 (-3390 2935);
PAINT ORANGE (-3390 2935);
FORCEPROP 2 LASTPIN (-3400 2875) $PN CD3
J 0
(-3390 2885);
DISPLAY 0.617021 (-3390 2885);
PAINT ORANGE (-3390 2885);
FORCEPROP 2 LASTPIN (-3400 2525) $PN CE4
J 0
(-3390 2535);
DISPLAY 0.617021 (-3390 2535);
PAINT ORANGE (-3390 2535);
FORCEPROP 2 LASTPIN (-3400 2475) $PN CE2
J 0
(-3390 2485);
DISPLAY 0.617021 (-3390 2485);
PAINT ORANGE (-3390 2485);
FORCEPROP 2 LASTPIN (-3400 2425) $PN CK3
J 0
(-3390 2435);
DISPLAY 0.617021 (-3390 2435);
PAINT ORANGE (-3390 2435);
FORCEPROP 2 LASTPIN (-3400 2375) $PN CK1
J 0
(-3390 2385);
DISPLAY 0.617021 (-3390 2385);
PAINT ORANGE (-3390 2385);
FORCEPROP 2 LASTPIN (-3400 2025) $PN CP3
J 0
(-3390 2035);
DISPLAY 0.617021 (-3390 2035);
PAINT ORANGE (-3390 2035);
FORCEPROP 2 LASTPIN (-3400 1975) $PN CR2
J 0
(-3390 1985);
DISPLAY 0.617021 (-3390 1985);
PAINT ORANGE (-3390 1985);
FORCEPROP 2 LASTPIN (-3400 1925) $PN CU2
J 0
(-3390 1935);
DISPLAY 0.617021 (-3390 1935);
PAINT ORANGE (-3390 1935);
FORCEPROP 2 LASTPIN (-3400 1875) $PN CW4
J 0
(-3390 1885);
DISPLAY 0.617021 (-3390 1885);
PAINT ORANGE (-3390 1885);
FORCEPROP 2 LASTPIN (-3400 3275) $PN BM5
J 0
(-3390 3285);
DISPLAY 0.617021 (-3390 3285);
PAINT ORANGE (-3390 3285);
FORCEPROP 2 LASTPIN (-3400 3225) $PN BL4
J 0
(-3390 3235);
DISPLAY 0.617021 (-3390 3235);
PAINT ORANGE (-3390 3235);
FORCEPROP 2 LASTPIN (-3400 3175) $PN BP5
J 0
(-3390 3185);
DISPLAY 0.617021 (-3390 3185);
PAINT ORANGE (-3390 3185);
FORCEPROP 2 LASTPIN (-3400 3125) $PN BU4
J 0
(-3390 3135);
DISPLAY 0.617021 (-3390 3135);
PAINT ORANGE (-3390 3135);
FORCEPROP 2 LASTPIN (-3400 2775) $PN BW4
J 0
(-3390 2785);
DISPLAY 0.617021 (-3390 2785);
PAINT ORANGE (-3390 2785);
FORCEPROP 2 LASTPIN (-3400 2725) $PN CA4
J 0
(-3390 2735);
DISPLAY 0.617021 (-3390 2735);
PAINT ORANGE (-3390 2735);
FORCEPROP 2 LASTPIN (-3400 2675) $PN CB3
J 0
(-3390 2685);
DISPLAY 0.617021 (-3390 2685);
PAINT ORANGE (-3390 2685);
FORCEPROP 2 LASTPIN (-3400 2625) $PN CC2
J 0
(-3390 2635);
DISPLAY 0.617021 (-3390 2635);
PAINT ORANGE (-3390 2635);
FORCEPROP 2 LASTPIN (-3400 2275) $PN CF3
J 0
(-3390 2285);
DISPLAY 0.617021 (-3390 2285);
PAINT ORANGE (-3390 2285);
FORCEPROP 2 LASTPIN (-3400 2225) $PN CG2
J 0
(-3390 2235);
DISPLAY 0.617021 (-3390 2235);
PAINT ORANGE (-3390 2235);
FORCEPROP 2 LASTPIN (-3400 2175) $PN CL2
J 0
(-3390 2185);
DISPLAY 0.617021 (-3390 2185);
PAINT ORANGE (-3390 2185);
FORCEPROP 2 LASTPIN (-3400 2125) $PN CM1
J 0
(-3390 2135);
DISPLAY 0.617021 (-3390 2135);
PAINT ORANGE (-3390 2135);
FORCEPROP 2 LASTPIN (-3400 1775) $PN CT3
J 0
(-3390 1785);
DISPLAY 0.617021 (-3390 1785);
PAINT ORANGE (-3390 1785);
FORCEPROP 2 LASTPIN (-3400 1725) $PN CT1
J 0
(-3390 1735);
DISPLAY 0.617021 (-3390 1735);
PAINT ORANGE (-3390 1735);
FORCEPROP 2 LASTPIN (-3400 1675) $PN CV3
J 0
(-3390 1685);
DISPLAY 0.617021 (-3390 1685);
PAINT ORANGE (-3390 1685);
FORCEPROP 2 LASTPIN (-3400 1625) $PN CY3
J 0
(-3390 1635);
DISPLAY 0.617021 (-3390 1635);
PAINT ORANGE (-3390 1635);
FORCEPROP 2 LASTPIN (-4900 3525) $PN BJ10
J 2
(-4910 3535);
DISPLAY 0.617021 (-4910 3535);
PAINT ORANGE (-4910 3535);
FORCEPROP 2 LASTPIN (-4900 3475) $PN BJ8
J 2
(-4910 3485);
DISPLAY 0.617021 (-4910 3485);
PAINT ORANGE (-4910 3485);
FORCEPROP 2 LASTPIN (-4900 3425) $PN BM7
J 2
(-4910 3435);
DISPLAY 0.617021 (-4910 3435);
PAINT ORANGE (-4910 3435);
FORCEPROP 2 LASTPIN (-4900 3375) $PN BP9
J 2
(-4910 3385);
DISPLAY 0.617021 (-4910 3385);
PAINT ORANGE (-4910 3385);
FORCEPROP 2 LASTPIN (-4900 3025) $PN BP7
J 2
(-4910 3035);
DISPLAY 0.617021 (-4910 3035);
PAINT ORANGE (-4910 3035);
FORCEPROP 2 LASTPIN (-4900 2975) $PN BU6
J 2
(-4910 2985);
DISPLAY 0.617021 (-4910 2985);
PAINT ORANGE (-4910 2985);
FORCEPROP 2 LASTPIN (-4900 2925) $PN BW8
J 2
(-4910 2935);
DISPLAY 0.617021 (-4910 2935);
PAINT ORANGE (-4910 2935);
FORCEPROP 2 LASTPIN (-4900 2875) $PN BV9
J 2
(-4910 2885);
DISPLAY 0.617021 (-4910 2885);
PAINT ORANGE (-4910 2885);
FORCEPROP 2 LASTPIN (-4900 2525) $PN CC8
J 2
(-4910 2535);
DISPLAY 0.617021 (-4910 2535);
PAINT ORANGE (-4910 2535);
FORCEPROP 2 LASTPIN (-4900 2475) $PN CD7
J 2
(-4910 2485);
DISPLAY 0.617021 (-4910 2485);
PAINT ORANGE (-4910 2485);
FORCEPROP 2 LASTPIN (-4900 2425) $PN CF7
J 2
(-4910 2435);
DISPLAY 0.617021 (-4910 2435);
PAINT ORANGE (-4910 2435);
FORCEPROP 2 LASTPIN (-4900 2375) $PN CH7
J 2
(-4910 2385);
DISPLAY 0.617021 (-4910 2385);
PAINT ORANGE (-4910 2385);
FORCEPROP 2 LASTPIN (-4900 2025) $PN CL6
J 2
(-4910 2035);
DISPLAY 0.617021 (-4910 2035);
PAINT ORANGE (-4910 2035);
FORCEPROP 2 LASTPIN (-4900 1975) $PN CN8
J 2
(-4910 1985);
DISPLAY 0.617021 (-4910 1985);
PAINT ORANGE (-4910 1985);
FORCEPROP 2 LASTPIN (-4900 1925) $PN CM9
J 2
(-4910 1935);
DISPLAY 0.617021 (-4910 1935);
PAINT ORANGE (-4910 1935);
FORCEPROP 2 LASTPIN (-4900 1875) $PN CR8
J 2
(-4910 1885);
DISPLAY 0.617021 (-4910 1885);
PAINT ORANGE (-4910 1885);
FORCEPROP 2 LASTPIN (-4900 3275) $PN BK9
J 2
(-4910 3285);
DISPLAY 0.617021 (-4910 3285);
PAINT ORANGE (-4910 3285);
FORCEPROP 2 LASTPIN (-4900 3225) $PN BL8
J 2
(-4910 3235);
DISPLAY 0.617021 (-4910 3235);
PAINT ORANGE (-4910 3235);
FORCEPROP 2 LASTPIN (-4900 3175) $PN BN8
J 2
(-4910 3185);
DISPLAY 0.617021 (-4910 3185);
PAINT ORANGE (-4910 3185);
FORCEPROP 2 LASTPIN (-4900 3125) $PN BR8
J 2
(-4910 3135);
DISPLAY 0.617021 (-4910 3135);
PAINT ORANGE (-4910 3135);
FORCEPROP 2 LASTPIN (-4900 2775) $PN BT7
J 2
(-4910 2785);
DISPLAY 0.617021 (-4910 2785);
PAINT ORANGE (-4910 2785);
FORCEPROP 2 LASTPIN (-4900 2725) $PN BV7
J 2
(-4910 2735);
DISPLAY 0.617021 (-4910 2735);
PAINT ORANGE (-4910 2735);
FORCEPROP 2 LASTPIN (-4900 2675) $PN BY7
J 2
(-4910 2685);
DISPLAY 0.617021 (-4910 2685);
PAINT ORANGE (-4910 2685);
FORCEPROP 2 LASTPIN (-4900 2625) $PN BY9
J 2
(-4910 2635);
DISPLAY 0.617021 (-4910 2635);
PAINT ORANGE (-4910 2635);
FORCEPROP 2 LASTPIN (-4900 2275) $PN CE8
J 2
(-4910 2285);
DISPLAY 0.617021 (-4910 2285);
PAINT ORANGE (-4910 2285);
FORCEPROP 2 LASTPIN (-4900 2225) $PN CE6
J 2
(-4910 2235);
DISPLAY 0.617021 (-4910 2235);
PAINT ORANGE (-4910 2235);
FORCEPROP 2 LASTPIN (-4900 2175) $PN CG8
J 2
(-4910 2185);
DISPLAY 0.617021 (-4910 2185);
PAINT ORANGE (-4910 2185);
FORCEPROP 2 LASTPIN (-4900 2125) $PN CK7
J 2
(-4910 2135);
DISPLAY 0.617021 (-4910 2135);
PAINT ORANGE (-4910 2135);
FORCEPROP 2 LASTPIN (-4900 1775) $PN CM7
J 2
(-4910 1785);
DISPLAY 0.617021 (-4910 1785);
PAINT ORANGE (-4910 1785);
FORCEPROP 2 LASTPIN (-4900 1725) $PN CP7
J 2
(-4910 1735);
DISPLAY 0.617021 (-4910 1735);
PAINT ORANGE (-4910 1735);
FORCEPROP 2 LASTPIN (-4900 1675) $PN CP9
J 2
(-4910 1685);
DISPLAY 0.617021 (-4910 1685);
PAINT ORANGE (-4910 1685);
FORCEPROP 2 LASTPIN (-4900 1625) $PN CT9
J 2
(-4910 1635);
DISPLAY 0.617021 (-4910 1635);
PAINT ORANGE (-4910 1635);
FORCEPROP 1 LAST PACK_TYPE BGA1
J 0
(-4850 3825);
PAINT SKYBLUE (-4850 3825);
DISPLAY INVISIBLE (-4850 3825);
FORCEPROP 2 LAST SEC_TYPE BGA1
J 0
(-4850 3825);
DISPLAY 1.021277 (-4850 3825);
PAINT ORANGE (-4850 3825);
DISPLAY INVISIBLE (-4850 3825);
FORCEPROP 2 LAST CDS_LIB chpset_lib
J 0
(-4150 2575);
PAINT ORANGE (-4150 2575);
DISPLAY INVISIBLE (-4150 2575);
FORCEPROP 2 LAST SEC 11
J 0
(-4850 3825);
DISPLAY 0.680851 (-4850 3825);
PAINT MONO (-4850 3825);
DISPLAY INVISIBLE (-4850 3825);
FORCEPROP 2 LAST CDS_LOCATION U2D1
J 0
(-4850 3775);
DISPLAY 0.617021 (-4850 3775);
PAINT AQUA (-4850 3775);
DISPLAY INVISIBLE (-4850 3775);
FORCEPROP 1 LAST PATH I68
J 0
(-4150 3725);
PAINT GREEN (-4150 3725);
DISPLAY INVISIBLE (-4150 3725);
FORCEADD TAP..1
R 2
(-5425 1975);
FORCEPROP 3 LASTPIN (-5375 1975) SIG_NAME TP_P3E_CPU1_PE2_RSR_RXP<2>
J 0
(-5365 1985);
DISPLAY 0.659574 (-5365 1985);
PAINT MONO (-5365 1985);
DISPLAY INVISIBLE (-5365 1985);
FORCEPROP 1 LASTPIN (-5375 1975) BN 2
J 2
(-5363 1983);
DISPLAY 0.617021 (-5363 1983);
PAINT GREEN (-5363 1983);
FORCEPROP 2 LAST CDS_LIB mstr_standard
J 0
(-5425 1975);
PAINT MONO (-5425 1975);
DISPLAY INVISIBLE (-5425 1975);
FORCEPROP 1 LAST BODY_TYPE PLUMBING
J 2
(-5425 2025);
DISPLAY 1.446809 (-5425 2025);
PAINT GREEN (-5425 2025);
DISPLAY INVISIBLE (-5425 2025);
FORCEPROP 1 LAST HDL_TAP TRUE
J 2
(-5750 1850);
DISPLAY 1.446809 (-5750 1850);
PAINT GREEN (-5750 1850);
DISPLAY INVISIBLE (-5750 1850);
FORCEPROP 1 LAST PATH I7
J 2
(-5423 1975);
DISPLAY 0.872340 (-5423 1975);
PAINT GREEN (-5423 1975);
DISPLAY INVISIBLE (-5423 1975);
FORCEADD TAP..1
R 2
(-5425 1925);
FORCEPROP 3 LASTPIN (-5375 1925) SIG_NAME TP_P3E_CPU1_PE2_RSR_RXP<1>
J 0
(-5365 1935);
DISPLAY 0.659574 (-5365 1935);
PAINT MONO (-5365 1935);
DISPLAY INVISIBLE (-5365 1935);
FORCEPROP 1 LASTPIN (-5375 1925) BN 1
J 2
(-5363 1933);
DISPLAY 0.617021 (-5363 1933);
PAINT GREEN (-5363 1933);
FORCEPROP 2 LAST CDS_LIB mstr_standard
J 0
(-5425 1925);
PAINT MONO (-5425 1925);
DISPLAY INVISIBLE (-5425 1925);
FORCEPROP 1 LAST BODY_TYPE PLUMBING
J 2
(-5425 1975);
DISPLAY 1.446809 (-5425 1975);
PAINT GREEN (-5425 1975);
DISPLAY INVISIBLE (-5425 1975);
FORCEPROP 1 LAST HDL_TAP TRUE
J 2
(-5750 1800);
DISPLAY 1.446809 (-5750 1800);
PAINT GREEN (-5750 1800);
DISPLAY INVISIBLE (-5750 1800);
FORCEPROP 1 LAST PATH I8
J 2
(-5423 1925);
DISPLAY 0.872340 (-5423 1925);
PAINT GREEN (-5423 1925);
DISPLAY INVISIBLE (-5423 1925);
FORCEADD TAP..1
R 2
(-5425 1875);
FORCEPROP 3 LASTPIN (-5375 1875) SIG_NAME TP_P3E_CPU1_PE2_RSR_RXP<0>
J 0
(-5365 1885);
DISPLAY 0.659574 (-5365 1885);
PAINT MONO (-5365 1885);
DISPLAY INVISIBLE (-5365 1885);
FORCEPROP 1 LASTPIN (-5375 1875) BN 0
J 2
(-5363 1883);
DISPLAY 0.617021 (-5363 1883);
PAINT GREEN (-5363 1883);
FORCEPROP 2 LAST CDS_LIB mstr_standard
J 0
(-5425 1875);
PAINT MONO (-5425 1875);
DISPLAY INVISIBLE (-5425 1875);
FORCEPROP 1 LAST BODY_TYPE PLUMBING
J 2
(-5425 1925);
DISPLAY 1.446809 (-5425 1925);
PAINT GREEN (-5425 1925);
DISPLAY INVISIBLE (-5425 1925);
FORCEPROP 1 LAST HDL_TAP TRUE
J 2
(-5750 1750);
DISPLAY 1.446809 (-5750 1750);
PAINT GREEN (-5750 1750);
DISPLAY INVISIBLE (-5750 1750);
FORCEPROP 1 LAST PATH I9
J 2
(-5423 1875);
DISPLAY 0.872340 (-5423 1875);
PAINT GREEN (-5423 1875);
DISPLAY INVISIBLE (-5423 1875);
FORCEADD DESIGN_NOTE..1
(-4650 1325);
FORCEPROP 0 LAST L1 CPU SYMBOLS 1-30 ARE PRELIMINARY AND SUBJECT TO CHANGE
J 0
(-4850 1200);
DISPLAY 1.021277 (-4850 1200);
PAINT ORANGE (-4850 1200);
FORCEPROP 2 LAST CDS_LIB mstr_symbols
J 0
(-4650 1325);
PAINT ORANGE (-4650 1325);
DISPLAY INVISIBLE (-4650 1325);
FORCEPROP 1 LAST COMMENT_BODY TRUE
J 0
(-4625 1425);
DISPLAY 0.978723 (-4625 1425);
PAINT ORANGE (-4625 1425);
DISPLAY INVISIBLE (-4625 1425);
FORCEADD PRELIM..10
(-4140 2565);
PAINT GRAY (-4140 2565);
FORCEPROP 2 LAST CDS_LIB mstr_misc
J 0
(-4140 2565);
PAINT ORANGE (-4140 2565);
DISPLAY INVISIBLE (-4140 2565);
FORCEPROP 1 LAST COMMENT_BODY TRUE
J 0
(-4140 2565);
PAINT ORANGE (-4140 2565);
DISPLAY INVISIBLE (-4140 2565);
FORCEADD INTEL_CORP_BPAGE..1
(0 0);
FORCEPROP 1 LAST CDS_CON_LAST_MODIFIED Tue Dec 01 11:51:36 2015
J 0
(-1425 325);
DISPLAY 1.340426 (-1425 325);
PAINT GREEN (-1425 325);
DISPLAY INVISIBLE (-1425 325);
FORCEPROP 1 LAST CUSTOM_TXT_CDS <CURRENT_DESIGN_SHEET> OF <TOTAL_DESIGN_SHEETS>
J 0
(-500 25);
PAINT GREEN (-500 25);
FORCEPROP 1 LAST CUSTOM_TXT_CDS <CON_LAST_MODIFIED>
J 0
(-1925 350);
PAINT GREEN (-1925 350);
FORCEPROP 2 LAST CUSTOM_TXT_CDS <XR_PAGE_TITLE>
J 0
(-7890 5250);
DISPLAY 0.638298 (-7890 5250);
PAINT PINK (-7890 5250);
DISPLAY INVISIBLE (-7890 5250);
FORCEPROP 1 LAST SCH_ADDRESS3 Santa Clara, CA 95052-8119
J 0
(-3975 25);
DISPLAY 0.617021 (-3975 25);
PAINT GREEN (-3975 25);
FORCEPROP 1 LAST SCH_ADDRESS2 P.O. BOX 58119
J 0
(-3975 75);
DISPLAY 0.617021 (-3975 75);
PAINT GREEN (-3975 75);
FORCEPROP 1 LAST SCH_ADDRESS1 2200 Mission College Blvd.
J 0
(-3975 125);
DISPLAY 0.617021 (-3975 125);
PAINT GREEN (-3975 125);
FORCEPROP 1 LAST SCH_TITLE SKYLAKE - SKT1 - 11 OF 21
J 0
(-7950 50);
DISPLAY 1.212766 (-7950 50);
PAINT GREEN (-7950 50);
FORCEPROP 1 LAST SCH_NUMBER H4694802
J 0
(-1300 150);
DISPLAY 1.212766 (-1300 150);
PAINT YELLOW (-1300 150);
FORCEPROP 1 LAST SCH_DEPT BESD
J 1
(-4450 100);
DISPLAY 1.212766 (-4450 100);
PAINT YELLOW (-4450 100);
FORCEPROP 1 LAST SCH_REV 2.420
J 0
(-250 150);
DISPLAY 0.978723 (-250 150);
PAINT YELLOW (-250 150);
FORCEPROP 2 LAST CDS_LIB mstr_symbols
J 0
(0 0);
PAINT ORANGE (0 0);
DISPLAY INVISIBLE (0 0);
FORCEPROP 2 LAST PAGE_BORDER TRUE
J 0
(-7890 5250);
DISPLAY 0.851064 (-7890 5250);
PAINT PINK (-7890 5250);
DISPLAY INVISIBLE (-7890 5250);
FORCEPROP 1 LAST COMMENT_BODY TRUE
J 0
(12 12);
DISPLAY 0.638298 (12 12);
PAINT GREEN (12 12);
DISPLAY INVISIBLE (12 12);
FORCEPROP 2 LAST CDS_XR_PAGE_TITLE CR-65 : @BASEBOARD_FAB2_LIB.BASEBOARD_FAB2(SCH_1):PAGE65
J 0
(-7890 5250);
DISPLAY 0.638298 (-7890 5250);
PAINT PINK (-7890 5250);
DISPLAY INVISIBLE (-7890 5250);
WIRE 17 -1 (-2750 3300)(-2750 3500);
WIRE 17 -1 (-2750 3250)(-2750 3300);
WIRE 17 -1 (-2750 3500)(-1575 3500);
FORCEPROP 2 LAST SIG_NAME TP_P3E_CPU1_PE2_RSR_TXN<15:0>
J 0
(-2710 3510);
DISPLAY 0.617021 (-2710 3510);
PAINT ORANGE (-2710 3510);
FORCEPROP 2 LASTPROP $XRERR UNIQUE?
J 0
(-1545 3500);
DISPLAY 0.638298 (-1545 3500);
PAINT MONO (-1545 3500);
DISPLAY INVISIBLE (-1545 3500);
WIRE 17 -1 (-2750 3200)(-2750 3250);
WIRE 17 -1 (-2750 3150)(-2750 3200);
WIRE 17 -1 (-2750 2800)(-2750 3150);
WIRE 17 -1 (-2750 2750)(-2750 2800);
WIRE 17 -1 (-2750 2700)(-2750 2750);
WIRE 17 -1 (-2750 2650)(-2750 2700);
WIRE 17 -1 (-2750 2300)(-2750 2650);
WIRE 17 -1 (-2750 2250)(-2750 2300);
WIRE 17 -1 (-2750 2200)(-2750 2250);
WIRE 17 -1 (-2750 2150)(-2750 2200);
WIRE 17 -1 (-2750 1800)(-2750 2150);
WIRE 17 -1 (-2750 1750)(-2750 1800);
WIRE 17 -1 (-2750 1700)(-2750 1750);
WIRE 17 -1 (-2750 1650)(-2750 1700);
WIRE 17 -1 (-2900 3550)(-2900 3625);
WIRE 17 -1 (-2900 3500)(-2900 3550);
WIRE 17 -1 (-2900 3625)(-1575 3625);
FORCEPROP 2 LAST SIG_NAME TP_P3E_CPU1_PE2_RSR_TXP<15:0>
J 0
(-2710 3635);
DISPLAY 0.617021 (-2710 3635);
PAINT ORANGE (-2710 3635);
FORCEPROP 2 LASTPROP $XRERR UNIQUE?
J 0
(-1545 3625);
DISPLAY 0.638298 (-1545 3625);
PAINT MONO (-1545 3625);
DISPLAY INVISIBLE (-1545 3625);
WIRE 17 -1 (-2900 3450)(-2900 3500);
WIRE 17 -1 (-2900 3450)(-2900 3400);
WIRE 17 -1 (-2900 3050)(-2900 3400);
WIRE 17 -1 (-2900 3000)(-2900 3050);
WIRE 17 -1 (-2900 2950)(-2900 3000);
WIRE 17 -1 (-2900 2900)(-2900 2950);
WIRE 17 -1 (-2900 2550)(-2900 2900);
WIRE 17 -1 (-2900 2500)(-2900 2550);
WIRE 17 -1 (-2900 2450)(-2900 2500);
WIRE 17 -1 (-2900 2400)(-2900 2450);
WIRE 17 -1 (-2900 2050)(-2900 2400);
WIRE 17 -1 (-2900 2000)(-2900 2050);
WIRE 17 -1 (-2900 1950)(-2900 2000);
WIRE 17 -1 (-2900 1900)(-2900 1950);
WIRE 17 -1 (-5625 3300)(-5625 3600);
WIRE 17 -1 (-5625 3250)(-5625 3300);
WIRE 17 -1 (-6775 3600)(-5625 3600);
FORCEPROP 2 LAST SIG_NAME TP_P3E_CPU1_PE2_RSR_RXN<15:0>
J 0
(-6760 3610);
DISPLAY 0.617021 (-6760 3610);
PAINT ORANGE (-6760 3610);
FORCEPROP 2 LASTPROP $XRERR UNIQUE?
J 0
(-7015 3600);
DISPLAY 0.638298 (-7015 3600);
PAINT MONO (-7015 3600);
DISPLAY INVISIBLE (-7015 3600);
WIRE 17 -1 (-5625 3250)(-5625 3200);
WIRE 17 -1 (-5625 3200)(-5625 3150);
WIRE 17 -1 (-5625 3150)(-5625 2800);
WIRE 17 -1 (-5625 2800)(-5625 2750);
WIRE 17 -1 (-5625 2750)(-5625 2700);
WIRE 17 -1 (-5625 2700)(-5625 2650);
WIRE 17 -1 (-5625 2300)(-5625 2650);
WIRE 17 -1 (-5625 2250)(-5625 2300);
WIRE 17 -1 (-5625 2200)(-5625 2250);
WIRE 17 -1 (-5625 2200)(-5625 2150);
WIRE 17 -1 (-5625 2150)(-5625 1800);
WIRE 17 -1 (-5625 1800)(-5625 1750);
WIRE 17 -1 (-5625 1750)(-5625 1700);
WIRE 17 -1 (-5625 1700)(-5625 1650);
WIRE 17 -1 (-5475 3700)(-5475 3550);
WIRE 17 -1 (-6775 3700)(-5475 3700);
FORCEPROP 2 LAST SIG_NAME TP_P3E_CPU1_PE2_RSR_RXP<15:0>
J 0
(-6760 3710);
DISPLAY 0.617021 (-6760 3710);
PAINT ORANGE (-6760 3710);
FORCEPROP 2 LASTPROP $XRERR UNIQUE?
J 0
(-7015 3700);
DISPLAY 0.638298 (-7015 3700);
PAINT MONO (-7015 3700);
DISPLAY INVISIBLE (-7015 3700);
WIRE 17 -1 (-5475 3550)(-5475 3500);
WIRE 17 -1 (-5475 3500)(-5475 3450);
WIRE 17 -1 (-5475 3450)(-5475 3400);
WIRE 17 -1 (-5475 3400)(-5475 3050);
WIRE 17 -1 (-5475 3050)(-5475 3000);
WIRE 17 -1 (-5475 3000)(-5475 2950);
WIRE 17 -1 (-5475 2950)(-5475 2900);
WIRE 17 -1 (-5475 2900)(-5475 2550);
WIRE 17 -1 (-5475 2550)(-5475 2500);
WIRE 17 -1 (-5475 2500)(-5475 2450);
WIRE 17 -1 (-5475 2450)(-5475 2400);
WIRE 17 -1 (-5475 2050)(-5475 2400);
WIRE 17 -1 (-5475 2000)(-5475 2050);
WIRE 17 -1 (-5475 2000)(-5475 1950);
WIRE 17 -1 (-5475 1950)(-5475 1900);
WIRE 16 -1 (-5375 1875)(-4900 1875);
WIRE 16 -1 (-5375 1925)(-4900 1925);
WIRE 16 -1 (-5375 1975)(-4900 1975);
WIRE 16 -1 (-5375 2025)(-4900 2025);
WIRE 16 -1 (-4900 1625)(-5525 1625);
WIRE 16 -1 (-4900 1675)(-5525 1675);
WIRE 16 -1 (-4900 1725)(-5525 1725);
WIRE 16 -1 (-4900 1775)(-5525 1775);
WIRE 16 -1 (-4900 2375)(-5375 2375);
WIRE 16 -1 (-5375 2425)(-4900 2425);
WIRE 16 -1 (-5375 2475)(-4900 2475);
WIRE 16 -1 (-5375 2525)(-4900 2525);
WIRE 16 -1 (-5375 2875)(-4900 2875);
WIRE 16 -1 (-5375 2925)(-4900 2925);
WIRE 16 -1 (-5375 2975)(-4900 2975);
WIRE 16 -1 (-5375 3025)(-4900 3025);
WIRE 16 -1 (-5375 3375)(-4900 3375);
WIRE 16 -1 (-5375 3425)(-4900 3425);
WIRE 16 -1 (-5375 3475)(-4900 3475);
WIRE 16 -1 (-5375 3525)(-4900 3525);
WIRE 16 -1 (-4900 2125)(-5525 2125);
WIRE 16 -1 (-5525 2175)(-4900 2175);
WIRE 16 -1 (-5525 2225)(-4900 2225);
WIRE 16 -1 (-5525 2275)(-4900 2275);
WIRE 16 -1 (-5525 2625)(-4900 2625);
WIRE 16 -1 (-5525 2675)(-4900 2675);
WIRE 16 -1 (-5525 2725)(-4900 2725);
WIRE 16 -1 (-5525 2775)(-4900 2775);
WIRE 16 -1 (-5525 3125)(-4900 3125);
WIRE 16 -1 (-5525 3175)(-4900 3175);
WIRE 16 -1 (-5525 3225)(-4900 3225);
WIRE 16 -1 (-5525 3275)(-4900 3275);
WIRE 16 -1 (-3400 1875)(-3000 1875);
WIRE 16 -1 (-3000 1925)(-3400 1925);
WIRE 16 -1 (-3400 1975)(-3000 1975);
WIRE 16 -1 (-3000 2025)(-3400 2025);
WIRE 16 -1 (-2850 1625)(-3400 1625);
WIRE 16 -1 (-2850 1675)(-3400 1675);
WIRE 16 -1 (-2850 1725)(-3400 1725);
WIRE 16 -1 (-2850 1775)(-3400 1775);
WIRE 16 -1 (-3000 2375)(-3400 2375);
WIRE 16 -1 (-3000 2425)(-3400 2425);
WIRE 16 -1 (-3000 2475)(-3400 2475);
WIRE 16 -1 (-3000 2525)(-3400 2525);
WIRE 16 -1 (-3000 2875)(-3400 2875);
WIRE 16 -1 (-3000 2925)(-3400 2925);
WIRE 16 -1 (-3000 2975)(-3400 2975);
WIRE 16 -1 (-3000 3025)(-3400 3025);
WIRE 16 -1 (-3000 3375)(-3400 3375);
WIRE 16 -1 (-3400 3425)(-3000 3425);
WIRE 16 -1 (-3400 3475)(-3000 3475);
WIRE 16 -1 (-3000 3525)(-3400 3525);
WIRE 16 -1 (-2850 2125)(-3400 2125);
WIRE 16 -1 (-2850 2175)(-3400 2175);
WIRE 16 -1 (-3400 2225)(-2850 2225);
WIRE 16 -1 (-3400 2275)(-2850 2275);
WIRE 16 -1 (-2850 2625)(-3400 2625);
WIRE 16 -1 (-3400 2675)(-2850 2675);
WIRE 16 -1 (-2850 2725)(-3400 2725);
WIRE 16 -1 (-2850 2775)(-3400 2775);
WIRE 16 -1 (-3400 3125)(-2850 3125);
WIRE 16 -1 (-2850 3175)(-3400 3175);
WIRE 16 -1 (-2850 3225)(-3400 3225);
WIRE 16 -1 (-2850 3275)(-3400 3275);
FORCENOTE
ROOM=CPU1
(-7900 375) 0;
DISPLAY LEFT (-7900 375);
DISPLAY 1.723404 (-7900 375);
PAINT PURPLE (-7900 375);
FORCENOTE
BOM_COST=PROC_SOCKET
(-7900 250) 0;
DISPLAY LEFT (-7900 250);
DISPLAY 1.723404 (-7900 250);
PAINT PURPLE (-7900 250);
QUIT
